FILE_TYPE = MACRO_DRAWING;
SET COLOR_WIRE YELLOW;
SET COLOR_PROP MONO;
SET COLOR_DOT WHITE;
SET COLOR_ARC YELLOW;
SET COLOR_BODY GREEN;
SET COLOR_NOTE MONO;
SET PROP_DISPLAY VALUE;
SET PAGE_NUMBER P188;
FORCEADD OFFPAGE..3
(-2450 2900);
FORCEPROP 2 LAST $XR1 188 
J 0
(-2116 2900);
DISPLAY 0.638298 (-2116 2900);
PAINT MONO (-2116 2900);
FORCEPROP 2 LAST $XR0 120 
J 0
(-2236 2900);
DISPLAY 0.638298 (-2236 2900);
PAINT MONO (-2236 2900);
FORCEPROP 1 LAST COMMENT_BODY TRUE
J 0
(-2500 2800);
DISPLAY 0.872340 (-2500 2800);
PAINT GREEN (-2500 2800);
DISPLAY INVISIBLE (-2500 2800);
FORCEPROP 1 LAST OFFPAGE TRUE
J 0
(-2125 2775);
DISPLAY 0.872340 (-2125 2775);
PAINT GREEN (-2125 2775);
DISPLAY INVISIBLE (-2125 2775);
FORCEPROP 2 LAST PATH I100
J 0
(-2250 2975);
DISPLAY 1.021277 (-2250 2975);
PAINT ORANGE (-2250 2975);
DISPLAY INVISIBLE (-2250 2975);
FORCEPROP 2 LAST CDS_LIB mstr_standard
J 0
(-2450 2900);
PAINT ORANGE (-2450 2900);
DISPLAY INVISIBLE (-2450 2900);
FORCEPROP 2 LAST BOM_COST SB
J 0
(-2700 2950);
DISPLAY 1.361702 (-2700 2950);
PAINT ORANGE (-2700 2950);
DISPLAY INVISIBLE (-2700 2950);
FORCEPROP 2 LAST ROOM SB
J 0
(-2700 2950);
DISPLAY 1.361702 (-2700 2950);
PAINT ORANGE (-2700 2950);
DISPLAY INVISIBLE (-2700 2950);
FORCEADD OFFPAGE..3
(-2450 3200);
FORCEPROP 2 LAST $XR1 188 
J 0
(-2116 3200);
DISPLAY 0.638298 (-2116 3200);
PAINT MONO (-2116 3200);
FORCEPROP 2 LAST $XR0 120 
J 0
(-2236 3200);
DISPLAY 0.638298 (-2236 3200);
PAINT MONO (-2236 3200);
FORCEPROP 2 LAST ROOM SB
J 0
(-2700 3250);
DISPLAY 1.361702 (-2700 3250);
PAINT ORANGE (-2700 3250);
DISPLAY INVISIBLE (-2700 3250);
FORCEPROP 2 LAST BOM_COST SB
J 0
(-2700 3250);
DISPLAY 1.361702 (-2700 3250);
PAINT ORANGE (-2700 3250);
DISPLAY INVISIBLE (-2700 3250);
FORCEPROP 2 LAST CDS_LIB mstr_standard
J 0
(-2450 3200);
PAINT ORANGE (-2450 3200);
DISPLAY INVISIBLE (-2450 3200);
FORCEPROP 2 LAST PATH I101
J 0
(-2250 3275);
DISPLAY 1.021277 (-2250 3275);
PAINT ORANGE (-2250 3275);
DISPLAY INVISIBLE (-2250 3275);
FORCEPROP 1 LAST OFFPAGE TRUE
J 0
(-2125 3075);
DISPLAY 0.872340 (-2125 3075);
PAINT GREEN (-2125 3075);
DISPLAY INVISIBLE (-2125 3075);
FORCEPROP 1 LAST COMMENT_BODY TRUE
J 0
(-2500 3100);
DISPLAY 0.872340 (-2500 3100);
PAINT GREEN (-2500 3100);
DISPLAY INVISIBLE (-2500 3100);
FORCEADD OFFPAGE..3
(-2450 3500);
FORCEPROP 2 LAST $XR1 188 
J 0
(-2116 3500);
DISPLAY 0.638298 (-2116 3500);
PAINT MONO (-2116 3500);
FORCEPROP 2 LAST $XR0 120 
J 0
(-2236 3500);
DISPLAY 0.638298 (-2236 3500);
PAINT MONO (-2236 3500);
FORCEPROP 2 LAST CDS_LIB mstr_standard
J 0
(-2450 3500);
PAINT ORANGE (-2450 3500);
DISPLAY INVISIBLE (-2450 3500);
FORCEPROP 2 LAST BOM_COST SB
J 0
(-2700 3550);
DISPLAY 1.361702 (-2700 3550);
PAINT ORANGE (-2700 3550);
DISPLAY INVISIBLE (-2700 3550);
FORCEPROP 2 LAST ROOM SB
J 0
(-2700 3550);
DISPLAY 1.361702 (-2700 3550);
PAINT ORANGE (-2700 3550);
DISPLAY INVISIBLE (-2700 3550);
FORCEPROP 2 LAST PATH I102
J 0
(-2250 3575);
DISPLAY 1.021277 (-2250 3575);
PAINT ORANGE (-2250 3575);
DISPLAY INVISIBLE (-2250 3575);
FORCEPROP 1 LAST OFFPAGE TRUE
J 0
(-2125 3375);
DISPLAY 0.872340 (-2125 3375);
PAINT GREEN (-2125 3375);
DISPLAY INVISIBLE (-2125 3375);
FORCEPROP 1 LAST COMMENT_BODY TRUE
J 0
(-2500 3400);
DISPLAY 0.872340 (-2500 3400);
PAINT GREEN (-2500 3400);
DISPLAY INVISIBLE (-2500 3400);
FORCEADD OFFPAGE..3
(-2450 3800);
FORCEPROP 2 LAST $XR1 188 
J 0
(-2116 3800);
DISPLAY 0.638298 (-2116 3800);
PAINT MONO (-2116 3800);
FORCEPROP 2 LAST $XR0 120 
J 0
(-2236 3800);
DISPLAY 0.638298 (-2236 3800);
PAINT MONO (-2236 3800);
FORCEPROP 1 LAST COMMENT_BODY TRUE
J 0
(-2500 3700);
DISPLAY 0.872340 (-2500 3700);
PAINT GREEN (-2500 3700);
DISPLAY INVISIBLE (-2500 3700);
FORCEPROP 1 LAST OFFPAGE TRUE
J 0
(-2125 3675);
DISPLAY 0.872340 (-2125 3675);
PAINT GREEN (-2125 3675);
DISPLAY INVISIBLE (-2125 3675);
FORCEPROP 2 LAST PATH I103
J 0
(-2250 3875);
DISPLAY 1.021277 (-2250 3875);
PAINT ORANGE (-2250 3875);
DISPLAY INVISIBLE (-2250 3875);
FORCEPROP 2 LAST ROOM SB
J 0
(-2700 3850);
DISPLAY 1.361702 (-2700 3850);
PAINT ORANGE (-2700 3850);
DISPLAY INVISIBLE (-2700 3850);
FORCEPROP 2 LAST BOM_COST SB
J 0
(-2700 3850);
DISPLAY 1.361702 (-2700 3850);
PAINT ORANGE (-2700 3850);
DISPLAY INVISIBLE (-2700 3850);
FORCEPROP 2 LAST CDS_LIB mstr_standard
J 0
(-2450 3800);
PAINT ORANGE (-2450 3800);
DISPLAY INVISIBLE (-2450 3800);
FORCEADD OFFPAGE..6
(-1400 2475);
FORCEPROP 2 LAST $XR1 188 
J 0
(-1800 2475);
DISPLAY 0.638298 (-1800 2475);
PAINT MONO (-1800 2475);
FORCEPROP 2 LAST $XR0 120 
J 0
(-1680 2475);
DISPLAY 0.638298 (-1680 2475);
PAINT MONO (-1680 2475);
FORCEPROP 2 LAST CDS_LIB mstr_standard
J 0
(-1400 2475);
PAINT ORANGE (-1400 2475);
DISPLAY INVISIBLE (-1400 2475);
FORCEPROP 2 LAST ROOM SB
J 0
(-1650 2525);
DISPLAY 1.361702 (-1650 2525);
PAINT ORANGE (-1650 2525);
DISPLAY INVISIBLE (-1650 2525);
FORCEPROP 2 LAST BOM_COST SB
J 0
(-1650 2525);
DISPLAY 1.361702 (-1650 2525);
PAINT ORANGE (-1650 2525);
DISPLAY INVISIBLE (-1650 2525);
FORCEPROP 2 LAST PATH I104
J 0
(-1350 2550);
DISPLAY 1.021277 (-1350 2550);
PAINT ORANGE (-1350 2550);
DISPLAY INVISIBLE (-1350 2550);
FORCEPROP 1 LAST OFFPAGE TRUE
J 0
(-1075 2350);
DISPLAY 0.872340 (-1075 2350);
PAINT GREEN (-1075 2350);
DISPLAY INVISIBLE (-1075 2350);
FORCEPROP 1 LAST COMMENT_BODY TRUE
J 0
(-1300 2400);
DISPLAY 0.872340 (-1300 2400);
PAINT GREEN (-1300 2400);
DISPLAY INVISIBLE (-1300 2400);
FORCEADD OFFPAGE..1
(-1400 2525);
FORCEPROP 2 LAST $XR1 188 
J 0
(-1802 2525);
DISPLAY 0.638298 (-1802 2525);
PAINT MONO (-1802 2525);
FORCEPROP 2 LAST $XR0 120 
J 0
(-1682 2525);
DISPLAY 0.638298 (-1682 2525);
PAINT MONO (-1682 2525);
FORCEPROP 2 LAST CDS_LIB mstr_standard
J 0
(-1400 2525);
PAINT ORANGE (-1400 2525);
DISPLAY INVISIBLE (-1400 2525);
FORCEPROP 2 LAST BOM_COST SB
J 0
(-1650 2575);
DISPLAY 1.361702 (-1650 2575);
PAINT ORANGE (-1650 2575);
DISPLAY INVISIBLE (-1650 2575);
FORCEPROP 2 LAST ROOM SB
J 0
(-1650 2575);
DISPLAY 1.361702 (-1650 2575);
PAINT ORANGE (-1650 2575);
DISPLAY INVISIBLE (-1650 2575);
FORCEPROP 2 LAST PATH I105
J 0
(-1350 2600);
DISPLAY 1.021277 (-1350 2600);
PAINT ORANGE (-1350 2600);
DISPLAY INVISIBLE (-1350 2600);
FORCEPROP 1 LAST OFFPAGE TRUE
J 0
(-1075 2400);
DISPLAY 0.872340 (-1075 2400);
PAINT GREEN (-1075 2400);
DISPLAY INVISIBLE (-1075 2400);
FORCEPROP 1 LAST COMMENT_BODY TRUE
J 0
(-1275 2425);
DISPLAY 0.872340 (-1275 2425);
PAINT GREEN (-1275 2425);
DISPLAY INVISIBLE (-1275 2425);
FORCEADD OFFPAGE..6
(-1400 2325);
FORCEPROP 2 LAST $XR1 188 
J 0
(-1800 2325);
DISPLAY 0.638298 (-1800 2325);
PAINT MONO (-1800 2325);
FORCEPROP 2 LAST $XR0 120 
J 0
(-1680 2325);
DISPLAY 0.638298 (-1680 2325);
PAINT MONO (-1680 2325);
FORCEPROP 2 LAST BOM_COST SB
J 0
(-1650 2375);
DISPLAY 1.361702 (-1650 2375);
PAINT ORANGE (-1650 2375);
DISPLAY INVISIBLE (-1650 2375);
FORCEPROP 2 LAST ROOM SB
J 0
(-1650 2375);
DISPLAY 1.361702 (-1650 2375);
PAINT ORANGE (-1650 2375);
DISPLAY INVISIBLE (-1650 2375);
FORCEPROP 2 LAST CDS_LIB mstr_standard
J 0
(-1400 2325);
PAINT ORANGE (-1400 2325);
DISPLAY INVISIBLE (-1400 2325);
FORCEPROP 2 LAST PATH I106
J 0
(-1350 2400);
DISPLAY 1.021277 (-1350 2400);
PAINT ORANGE (-1350 2400);
DISPLAY INVISIBLE (-1350 2400);
FORCEPROP 1 LAST OFFPAGE TRUE
J 0
(-1075 2200);
DISPLAY 0.872340 (-1075 2200);
PAINT GREEN (-1075 2200);
DISPLAY INVISIBLE (-1075 2200);
FORCEPROP 1 LAST COMMENT_BODY TRUE
J 0
(-1300 2250);
DISPLAY 0.872340 (-1300 2250);
PAINT GREEN (-1300 2250);
DISPLAY INVISIBLE (-1300 2250);
FORCEADD OFFPAGE..1
(-1400 2375);
FORCEPROP 2 LAST $XR1 188 
J 0
(-1802 2375);
DISPLAY 0.638298 (-1802 2375);
PAINT MONO (-1802 2375);
FORCEPROP 2 LAST $XR0 120 
J 0
(-1682 2375);
DISPLAY 0.638298 (-1682 2375);
PAINT MONO (-1682 2375);
FORCEPROP 2 LAST CDS_LIB mstr_standard
J 0
(-1400 2375);
PAINT ORANGE (-1400 2375);
DISPLAY INVISIBLE (-1400 2375);
FORCEPROP 2 LAST BOM_COST SB
J 0
(-1650 2425);
DISPLAY 1.361702 (-1650 2425);
PAINT ORANGE (-1650 2425);
DISPLAY INVISIBLE (-1650 2425);
FORCEPROP 2 LAST ROOM SB
J 0
(-1650 2425);
DISPLAY 1.361702 (-1650 2425);
PAINT ORANGE (-1650 2425);
DISPLAY INVISIBLE (-1650 2425);
FORCEPROP 2 LAST PATH I107
J 0
(-1350 2450);
DISPLAY 1.021277 (-1350 2450);
PAINT ORANGE (-1350 2450);
DISPLAY INVISIBLE (-1350 2450);
FORCEPROP 1 LAST OFFPAGE TRUE
J 0
(-1075 2250);
DISPLAY 0.872340 (-1075 2250);
PAINT GREEN (-1075 2250);
DISPLAY INVISIBLE (-1075 2250);
FORCEPROP 1 LAST COMMENT_BODY TRUE
J 0
(-1275 2275);
DISPLAY 0.872340 (-1275 2275);
PAINT GREEN (-1275 2275);
DISPLAY INVISIBLE (-1275 2275);
FORCEADD OFFPAGE..1
(-1400 2825);
FORCEPROP 2 LAST $XR1 188 
J 0
(-1802 2825);
DISPLAY 0.638298 (-1802 2825);
PAINT MONO (-1802 2825);
FORCEPROP 2 LAST $XR0 120 
J 0
(-1682 2825);
DISPLAY 0.638298 (-1682 2825);
PAINT MONO (-1682 2825);
FORCEPROP 2 LAST ROOM SB
J 0
(-1650 2875);
DISPLAY 1.361702 (-1650 2875);
PAINT ORANGE (-1650 2875);
DISPLAY INVISIBLE (-1650 2875);
FORCEPROP 2 LAST BOM_COST SB
J 0
(-1650 2875);
DISPLAY 1.361702 (-1650 2875);
PAINT ORANGE (-1650 2875);
DISPLAY INVISIBLE (-1650 2875);
FORCEPROP 2 LAST CDS_LIB mstr_standard
J 0
(-1400 2825);
PAINT ORANGE (-1400 2825);
DISPLAY INVISIBLE (-1400 2825);
FORCEPROP 2 LAST PATH I108
J 0
(-1350 2900);
DISPLAY 1.021277 (-1350 2900);
PAINT ORANGE (-1350 2900);
DISPLAY INVISIBLE (-1350 2900);
FORCEPROP 1 LAST OFFPAGE TRUE
J 0
(-1075 2700);
DISPLAY 0.872340 (-1075 2700);
PAINT GREEN (-1075 2700);
DISPLAY INVISIBLE (-1075 2700);
FORCEPROP 1 LAST COMMENT_BODY TRUE
J 0
(-1275 2725);
DISPLAY 0.872340 (-1275 2725);
PAINT GREEN (-1275 2725);
DISPLAY INVISIBLE (-1275 2725);
FORCEADD OFFPAGE..6
(-1400 2775);
FORCEPROP 2 LAST $XR1 188 
J 0
(-1800 2775);
DISPLAY 0.638298 (-1800 2775);
PAINT MONO (-1800 2775);
FORCEPROP 2 LAST $XR0 120 
J 0
(-1680 2775);
DISPLAY 0.638298 (-1680 2775);
PAINT MONO (-1680 2775);
FORCEPROP 2 LAST CDS_LIB mstr_standard
J 0
(-1400 2775);
PAINT ORANGE (-1400 2775);
DISPLAY INVISIBLE (-1400 2775);
FORCEPROP 2 LAST ROOM SB
J 0
(-1650 2825);
DISPLAY 1.361702 (-1650 2825);
PAINT ORANGE (-1650 2825);
DISPLAY INVISIBLE (-1650 2825);
FORCEPROP 2 LAST BOM_COST SB
J 0
(-1650 2825);
DISPLAY 1.361702 (-1650 2825);
PAINT ORANGE (-1650 2825);
DISPLAY INVISIBLE (-1650 2825);
FORCEPROP 2 LAST PATH I109
J 0
(-1350 2850);
DISPLAY 1.021277 (-1350 2850);
PAINT ORANGE (-1350 2850);
DISPLAY INVISIBLE (-1350 2850);
FORCEPROP 1 LAST OFFPAGE TRUE
J 0
(-1075 2650);
DISPLAY 0.872340 (-1075 2650);
PAINT GREEN (-1075 2650);
DISPLAY INVISIBLE (-1075 2650);
FORCEPROP 1 LAST COMMENT_BODY TRUE
J 0
(-1300 2700);
DISPLAY 0.872340 (-1300 2700);
PAINT GREEN (-1300 2700);
DISPLAY INVISIBLE (-1300 2700);
FORCEADD OFFPAGE..3
(1400 2325);
FORCEPROP 2 LAST $XR1 188 
J 0
(1734 2325);
DISPLAY 0.638298 (1734 2325);
PAINT MONO (1734 2325);
FORCEPROP 2 LAST $XR0 120 
J 0
(1614 2325);
DISPLAY 0.638298 (1614 2325);
PAINT MONO (1614 2325);
FORCEPROP 2 LAST CDS_LIB mstr_standard
J 0
(1400 2325);
PAINT ORANGE (1400 2325);
DISPLAY INVISIBLE (1400 2325);
FORCEPROP 2 LAST ROOM SB
J 0
(1150 2375);
DISPLAY 1.361702 (1150 2375);
PAINT ORANGE (1150 2375);
DISPLAY INVISIBLE (1150 2375);
FORCEPROP 2 LAST BOM_COST SB
J 0
(1150 2375);
DISPLAY 1.361702 (1150 2375);
PAINT ORANGE (1150 2375);
DISPLAY INVISIBLE (1150 2375);
FORCEPROP 2 LAST PATH I110
J 0
(1600 2400);
DISPLAY 1.021277 (1600 2400);
PAINT ORANGE (1600 2400);
DISPLAY INVISIBLE (1600 2400);
FORCEPROP 1 LAST OFFPAGE TRUE
J 0
(1725 2200);
DISPLAY 0.872340 (1725 2200);
PAINT GREEN (1725 2200);
DISPLAY INVISIBLE (1725 2200);
FORCEPROP 1 LAST COMMENT_BODY TRUE
J 0
(1350 2225);
DISPLAY 0.872340 (1350 2225);
PAINT GREEN (1350 2225);
DISPLAY INVISIBLE (1350 2225);
FORCEADD OFFPAGE..4
(1400 2375);
FORCEPROP 2 LAST $XR1 188 
J 0
(1706 2375);
DISPLAY 0.638298 (1706 2375);
PAINT MONO (1706 2375);
FORCEPROP 2 LAST $XR0 120 
J 0
(1586 2375);
DISPLAY 0.638298 (1586 2375);
PAINT MONO (1586 2375);
FORCEPROP 2 LAST BOM_COST SB
J 0
(1150 2425);
DISPLAY 1.361702 (1150 2425);
PAINT ORANGE (1150 2425);
DISPLAY INVISIBLE (1150 2425);
FORCEPROP 2 LAST ROOM SB
J 0
(1150 2425);
DISPLAY 1.361702 (1150 2425);
PAINT ORANGE (1150 2425);
DISPLAY INVISIBLE (1150 2425);
FORCEPROP 2 LAST CDS_LIB mstr_standard
J 0
(1400 2375);
PAINT ORANGE (1400 2375);
DISPLAY INVISIBLE (1400 2375);
FORCEPROP 2 LAST PATH I111
J 0
(1575 2450);
DISPLAY 1.021277 (1575 2450);
PAINT ORANGE (1575 2450);
DISPLAY INVISIBLE (1575 2450);
FORCEPROP 1 LAST OFFPAGE TRUE
J 0
(1725 2250);
DISPLAY 0.872340 (1725 2250);
PAINT GREEN (1725 2250);
DISPLAY INVISIBLE (1725 2250);
FORCEPROP 1 LAST COMMENT_BODY TRUE
J 0
(1375 2275);
DISPLAY 0.872340 (1375 2275);
PAINT GREEN (1375 2275);
DISPLAY INVISIBLE (1375 2275);
FORCEADD OFFPAGE..2
(1400 3525);
FORCEPROP 2 LAST $XR1 188 
J 0
(1709 3525);
DISPLAY 0.638298 (1709 3525);
PAINT MONO (1709 3525);
FORCEPROP 2 LAST $XR0 120 
J 0
(1589 3525);
DISPLAY 0.638298 (1589 3525);
PAINT MONO (1589 3525);
FORCEPROP 2 LAST CDS_LIB mstr_standard
J 0
(1400 3525);
PAINT ORANGE (1400 3525);
DISPLAY INVISIBLE (1400 3525);
FORCEPROP 2 LAST ROOM SB
J 0
(1150 3575);
DISPLAY 1.361702 (1150 3575);
PAINT ORANGE (1150 3575);
DISPLAY INVISIBLE (1150 3575);
FORCEPROP 2 LAST BOM_COST SB
J 0
(1150 3575);
DISPLAY 1.361702 (1150 3575);
PAINT ORANGE (1150 3575);
DISPLAY INVISIBLE (1150 3575);
FORCEPROP 2 LAST PATH I112
J 0
(1575 3600);
DISPLAY 1.021277 (1575 3600);
PAINT ORANGE (1575 3600);
DISPLAY INVISIBLE (1575 3600);
FORCEPROP 1 LAST OFFPAGE TRUE
J 0
(1725 3400);
DISPLAY 0.872340 (1725 3400);
PAINT GREEN (1725 3400);
DISPLAY INVISIBLE (1725 3400);
FORCEPROP 1 LAST COMMENT_BODY TRUE
J 0
(1355 3430);
DISPLAY 0.872340 (1355 3430);
PAINT GREEN (1355 3430);
DISPLAY INVISIBLE (1355 3430);
FORCEADD OFFPAGE..2
(1400 3575);
FORCEPROP 2 LAST $XR1 188 
J 0
(1709 3575);
DISPLAY 0.638298 (1709 3575);
PAINT MONO (1709 3575);
FORCEPROP 2 LAST $XR0 120 
J 0
(1589 3575);
DISPLAY 0.638298 (1589 3575);
PAINT MONO (1589 3575);
FORCEPROP 2 LAST BOM_COST SB
J 0
(1150 3625);
DISPLAY 1.361702 (1150 3625);
PAINT ORANGE (1150 3625);
DISPLAY INVISIBLE (1150 3625);
FORCEPROP 2 LAST ROOM SB
J 0
(1150 3625);
DISPLAY 1.361702 (1150 3625);
PAINT ORANGE (1150 3625);
DISPLAY INVISIBLE (1150 3625);
FORCEPROP 2 LAST CDS_LIB mstr_standard
J 0
(1400 3575);
PAINT ORANGE (1400 3575);
DISPLAY INVISIBLE (1400 3575);
FORCEPROP 2 LAST PATH I113
J 0
(1575 3650);
DISPLAY 1.021277 (1575 3650);
PAINT ORANGE (1575 3650);
DISPLAY INVISIBLE (1575 3650);
FORCEPROP 1 LAST OFFPAGE TRUE
J 0
(1725 3450);
DISPLAY 0.872340 (1725 3450);
PAINT GREEN (1725 3450);
DISPLAY INVISIBLE (1725 3450);
FORCEPROP 1 LAST COMMENT_BODY TRUE
J 0
(1355 3480);
DISPLAY 0.872340 (1355 3480);
PAINT GREEN (1355 3480);
DISPLAY INVISIBLE (1355 3480);
FORCEADD OFFPAGE..5
(-1400 2275);
FORCEPROP 2 LAST $XR1 188 
J 0
(-1805 2275);
DISPLAY 0.638298 (-1805 2275);
PAINT MONO (-1805 2275);
FORCEPROP 2 LAST $XR0 120 
J 0
(-1685 2275);
DISPLAY 0.638298 (-1685 2275);
PAINT MONO (-1685 2275);
FORCEPROP 1 LAST COMMENT_BODY TRUE
J 0
(-1300 2200);
DISPLAY 0.872340 (-1300 2200);
PAINT GREEN (-1300 2200);
DISPLAY INVISIBLE (-1300 2200);
FORCEPROP 1 LAST OFFPAGE TRUE
J 0
(-1075 2150);
DISPLAY 0.872340 (-1075 2150);
PAINT GREEN (-1075 2150);
DISPLAY INVISIBLE (-1075 2150);
FORCEPROP 2 LAST PATH I114
J 0
(-1350 2350);
DISPLAY 1.021277 (-1350 2350);
PAINT ORANGE (-1350 2350);
DISPLAY INVISIBLE (-1350 2350);
FORCEPROP 2 LAST CDS_LIB mstr_standard
J 0
(-1400 2275);
PAINT ORANGE (-1400 2275);
DISPLAY INVISIBLE (-1400 2275);
FORCEPROP 2 LAST BOM_COST SB
J 0
(-1650 2325);
DISPLAY 1.361702 (-1650 2325);
PAINT ORANGE (-1650 2325);
DISPLAY INVISIBLE (-1650 2325);
FORCEPROP 2 LAST ROOM SB
J 0
(-1650 2325);
DISPLAY 1.361702 (-1650 2325);
PAINT ORANGE (-1650 2325);
DISPLAY INVISIBLE (-1650 2325);
FORCEADD OFFPAGE..5
(-1400 2225);
FORCEPROP 2 LAST $XR1 188 
J 0
(-1775 2225);
DISPLAY 0.638298 (-1775 2225);
PAINT MONO (-1775 2225);
FORCEPROP 2 LAST $XR0 120 
J 0
(-1655 2225);
DISPLAY 0.638298 (-1655 2225);
PAINT MONO (-1655 2225);
FORCEPROP 1 LAST COMMENT_BODY TRUE
J 0
(-1300 2150);
DISPLAY 0.872340 (-1300 2150);
PAINT GREEN (-1300 2150);
DISPLAY INVISIBLE (-1300 2150);
FORCEPROP 1 LAST OFFPAGE TRUE
J 0
(-1075 2100);
DISPLAY 0.872340 (-1075 2100);
PAINT GREEN (-1075 2100);
DISPLAY INVISIBLE (-1075 2100);
FORCEPROP 2 LAST PATH I115
J 0
(-1350 2300);
DISPLAY 1.021277 (-1350 2300);
PAINT ORANGE (-1350 2300);
DISPLAY INVISIBLE (-1350 2300);
FORCEPROP 2 LAST CDS_LIB mstr_standard
J 0
(-1400 2225);
PAINT ORANGE (-1400 2225);
DISPLAY INVISIBLE (-1400 2225);
FORCEPROP 2 LAST ROOM SB
J 0
(-1650 2275);
DISPLAY 1.361702 (-1650 2275);
PAINT ORANGE (-1650 2275);
DISPLAY INVISIBLE (-1650 2275);
FORCEPROP 2 LAST BOM_COST SB
J 0
(-1650 2275);
DISPLAY 1.361702 (-1650 2275);
PAINT ORANGE (-1650 2275);
DISPLAY INVISIBLE (-1650 2275);
FORCEADD P3V3_STBY..1
(-3500 4200);
FORCEPROP 3 LASTPIN (-3500 4150) SIG_NAME P3V3_STBY\g
J 0
(-3490 4160);
DISPLAY 0.659574 (-3490 4160);
PAINT MONO (-3490 4160);
DISPLAY INVISIBLE (-3490 4160);
FORCEPROP 1 LAST HDL_POWER P3V3_STBY
J 0
(-3800 4075);
DISPLAY 0.872340 (-3800 4075);
PAINT ORANGE (-3800 4075);
DISPLAY INVISIBLE (-3800 4075);
FORCEPROP 1 LAST BODY_TYPE PLUMBING
J 0
(-3545 4157);
DISPLAY 0.340426 (-3545 4157);
PAINT GREEN (-3545 4157);
DISPLAY INVISIBLE (-3545 4157);
FORCEPROP 1 LAST PATH I116
J 0
(-3455 4202);
DISPLAY 0.340426 (-3455 4202);
PAINT GREEN (-3455 4202);
DISPLAY INVISIBLE (-3455 4202);
FORCEPROP 1 LAST SIZE 1B
J 0
(-3455 4222);
DISPLAY 0.340426 (-3455 4222);
PAINT GREEN (-3455 4222);
DISPLAY INVISIBLE (-3455 4222);
FORCEPROP 2 LAST CDS_LIB mstr_symbols
J 0
(-3500 4200);
PAINT ORANGE (-3500 4200);
DISPLAY INVISIBLE (-3500 4200);
FORCEPROP 1 LAST VOLTAGE 3.3V
J 0
(-3545 4157);
DISPLAY 0.340426 (-3545 4157);
PAINT SKYBLUE (-3545 4157);
DISPLAY INVISIBLE (-3545 4157);
FORCEADD OFFPAGE..2
(1425 2225);
FORCEPROP 2 LAST $XR0 250 
J 0
(1614 2225);
DISPLAY 0.638298 (1614 2225);
PAINT MONO (1614 2225);
FORCEPROP 2 LAST CDS_LIB mstr_standard
J 0
(1425 2225);
PAINT ORANGE (1425 2225);
DISPLAY INVISIBLE (1425 2225);
FORCEPROP 2 LAST BOM_COST SB
J 0
(1175 2275);
DISPLAY 1.361702 (1175 2275);
PAINT ORANGE (1175 2275);
DISPLAY INVISIBLE (1175 2275);
FORCEPROP 2 LAST ROOM SB
J 0
(1175 2275);
DISPLAY 1.361702 (1175 2275);
PAINT ORANGE (1175 2275);
DISPLAY INVISIBLE (1175 2275);
FORCEPROP 2 LAST PATH I117
J 0
(1600 2300);
DISPLAY 1.021277 (1600 2300);
PAINT ORANGE (1600 2300);
DISPLAY INVISIBLE (1600 2300);
FORCEPROP 1 LAST OFFPAGE TRUE
J 0
(1750 2100);
DISPLAY 0.872340 (1750 2100);
PAINT GREEN (1750 2100);
DISPLAY INVISIBLE (1750 2100);
FORCEPROP 1 LAST COMMENT_BODY TRUE
J 0
(1380 2130);
DISPLAY 0.872340 (1380 2130);
PAINT GREEN (1380 2130);
DISPLAY INVISIBLE (1380 2130);
FORCEADD OFFPAGE..2
(3775 3700);
FORCEPROP 2 LAST $XR0 118 
J 0
(3964 3700);
DISPLAY 0.638298 (3964 3700);
PAINT MONO (3964 3700);
FORCEPROP 2 LAST PATH I118
J 0
(3975 3750);
DISPLAY 1.021277 (3975 3750);
PAINT ORANGE (3975 3750);
DISPLAY INVISIBLE (3975 3750);
FORCEPROP 2 LAST CDS_LIB mstr_standard
J 0
(3775 3700);
PAINT ORANGE (3775 3700);
DISPLAY INVISIBLE (3775 3700);
FORCEPROP 1 LAST OFFPAGE TRUE
J 0
(4100 3575);
DISPLAY 0.872340 (4100 3575);
PAINT GREEN (4100 3575);
DISPLAY INVISIBLE (4100 3575);
FORCEPROP 1 LAST COMMENT_BODY TRUE
J 0
(3730 3605);
DISPLAY 0.872340 (3730 3605);
PAINT GREEN (3730 3605);
DISPLAY INVISIBLE (3730 3605);
FORCEADD OFFPAGE..2
(3775 3375);
FORCEPROP 2 LAST $XR0 118 
J 0
(3964 3375);
DISPLAY 0.638298 (3964 3375);
PAINT MONO (3964 3375);
FORCEPROP 2 LAST PATH I119
J 0
(3975 3425);
DISPLAY 1.021277 (3975 3425);
PAINT ORANGE (3975 3425);
DISPLAY INVISIBLE (3975 3425);
FORCEPROP 2 LAST CDS_LIB mstr_standard
J 0
(3775 3375);
PAINT ORANGE (3775 3375);
DISPLAY INVISIBLE (3775 3375);
FORCEPROP 1 LAST OFFPAGE TRUE
J 0
(4100 3250);
DISPLAY 0.872340 (4100 3250);
PAINT GREEN (4100 3250);
DISPLAY INVISIBLE (4100 3250);
FORCEPROP 1 LAST COMMENT_BODY TRUE
J 0
(3730 3280);
DISPLAY 0.872340 (3730 3280);
PAINT GREEN (3730 3280);
DISPLAY INVISIBLE (3730 3280);
FORCEADD CAP_A..2
(3075 3375);
FORCEPROP 1 LAST VOLTAGE 16V
J 0
(3075 3275);
DISPLAY 0.617021 (3075 3275);
PAINT SKYBLUE (3075 3275);
FORCEPROP 1 LAST MATERIAL X7R
J 0
(3075 3225);
DISPLAY 0.617021 (3075 3225);
PAINT SKYBLUE (3075 3225);
FORCEPROP 1 LAST PACK_TYPE 0402V
J 1
(3275 3275);
DISPLAY 0.617021 (3275 3275);
PAINT SKYBLUE (3275 3275);
FORCEPROP 1 LAST LOCATION C8C13
J 1
(3075 3475);
DISPLAY 0.617021 (3075 3475);
PAINT AQUA (3075 3475);
FORCEPROP 1 LAST TOLERANCE 10%
J 2
(3050 3225);
DISPLAY 0.617021 (3050 3225);
PAINT SKYBLUE (3050 3225);
FORCEPROP 1 LAST VALUE 0.1UF
J 2
(3075 3275);
DISPLAY 0.617021 (3075 3275);
PAINT SKYBLUE (3075 3275);
FORCEPROP 1 LASTPIN (2975 3375) $PN 1
J 0
(2965 3390);
DISPLAY 0.617021 (2965 3390);
PAINT ORANGE (2965 3390);
FORCEPROP 1 LASTPIN (3175 3375) $PN 2
J 0
(3160 3390);
DISPLAY 0.617021 (3160 3390);
PAINT ORANGE (3160 3390);
FORCEPROP 1 LAST PART_NUMBER A36096-030
J 1
(3075 3425);
DISPLAY 0.617021 (3075 3425);
PAINT BLUE (3075 3425);
FORCEPROP 1 LAST PATH I120
J 0
(3075 3575);
DISPLAY 0.978723 (3075 3575);
PAINT WHITE (3075 3575);
DISPLAY INVISIBLE (3075 3575);
FORCEPROP 2 LAST SEC 1
J 0
(3075 3525);
DISPLAY 0.680851 (3075 3525);
PAINT MONO (3075 3525);
DISPLAY INVISIBLE (3075 3525);
FORCEPROP 2 LAST SEC_TYPE 0402V
J 0
(3075 3625);
DISPLAY 1.021277 (3075 3625);
PAINT ORANGE (3075 3625);
DISPLAY INVISIBLE (3075 3625);
FORCEPROP 2 LAST CDS_SEC 1
J 0
(3075 3525);
PAINT ORANGE (3075 3525);
DISPLAY INVISIBLE (3075 3525);
FORCEPROP 2 LAST CDS_LIB dev_discrete
J 0
(3075 3375);
PAINT ORANGE (3075 3375);
DISPLAY INVISIBLE (3075 3375);
FORCEADD CAP_A..2
(3075 3700);
FORCEPROP 1 LASTPIN (2975 3700) $PN 1
J 0
(2965 3715);
DISPLAY 0.617021 (2965 3715);
PAINT ORANGE (2965 3715);
FORCEPROP 1 LAST LOCATION C8C12
J 1
(3075 3800);
DISPLAY 0.617021 (3075 3800);
PAINT AQUA (3075 3800);
FORCEPROP 1 LAST VALUE 0.1UF
J 2
(3075 3600);
DISPLAY 0.617021 (3075 3600);
PAINT SKYBLUE (3075 3600);
FORCEPROP 1 LAST VOLTAGE 16V
J 0
(3075 3600);
DISPLAY 0.617021 (3075 3600);
PAINT SKYBLUE (3075 3600);
FORCEPROP 1 LASTPIN (3175 3700) $PN 2
J 0
(3160 3715);
DISPLAY 0.617021 (3160 3715);
PAINT ORANGE (3160 3715);
FORCEPROP 1 LAST PART_NUMBER A36096-030
J 1
(3075 3750);
DISPLAY 0.617021 (3075 3750);
PAINT BLUE (3075 3750);
FORCEPROP 1 LAST PACK_TYPE 0402V
J 1
(3275 3600);
DISPLAY 0.617021 (3275 3600);
PAINT SKYBLUE (3275 3600);
FORCEPROP 1 LAST MATERIAL X7R
J 0
(3075 3550);
DISPLAY 0.617021 (3075 3550);
PAINT SKYBLUE (3075 3550);
FORCEPROP 1 LAST TOLERANCE 10%
J 2
(3050 3550);
DISPLAY 0.617021 (3050 3550);
PAINT SKYBLUE (3050 3550);
FORCEPROP 1 LAST PATH I121
J 0
(3075 3900);
DISPLAY 0.978723 (3075 3900);
PAINT WHITE (3075 3900);
DISPLAY INVISIBLE (3075 3900);
FORCEPROP 2 LAST SEC 1
J 0
(3075 3850);
DISPLAY 0.680851 (3075 3850);
PAINT MONO (3075 3850);
DISPLAY INVISIBLE (3075 3850);
FORCEPROP 2 LAST SEC_TYPE 0402V
J 0
(3075 3950);
DISPLAY 1.021277 (3075 3950);
PAINT ORANGE (3075 3950);
DISPLAY INVISIBLE (3075 3950);
FORCEPROP 2 LAST CDS_SEC 1
J 0
(3075 3850);
PAINT ORANGE (3075 3850);
DISPLAY INVISIBLE (3075 3850);
FORCEPROP 2 LAST CDS_LIB dev_discrete
J 0
(3075 3700);
PAINT ORANGE (3075 3700);
DISPLAY INVISIBLE (3075 3700);
FORCEADD OFFPAGE..1
(2375 3700);
FORCEPROP 2 LAST $XR0 188 
J 0
(2093 3700);
DISPLAY 0.638298 (2093 3700);
PAINT MONO (2093 3700);
FORCEPROP 2 LAST PATH I122
J 0
(2100 3750);
DISPLAY 1.021277 (2100 3750);
PAINT ORANGE (2100 3750);
DISPLAY INVISIBLE (2100 3750);
FORCEPROP 2 LAST CDS_LIB mstr_standard
J 0
(2375 3700);
PAINT ORANGE (2375 3700);
DISPLAY INVISIBLE (2375 3700);
FORCEPROP 1 LAST OFFPAGE TRUE
J 0
(2700 3575);
DISPLAY 0.872340 (2700 3575);
PAINT GREEN (2700 3575);
DISPLAY INVISIBLE (2700 3575);
FORCEPROP 1 LAST COMMENT_BODY TRUE
J 0
(2500 3600);
DISPLAY 0.872340 (2500 3600);
PAINT GREEN (2500 3600);
DISPLAY INVISIBLE (2500 3600);
FORCEADD OFFPAGE..1
(2375 3375);
FORCEPROP 2 LAST $XR0 188 
J 0
(2093 3375);
DISPLAY 0.638298 (2093 3375);
PAINT MONO (2093 3375);
FORCEPROP 2 LAST PATH I123
J 0
(2100 3425);
DISPLAY 1.021277 (2100 3425);
PAINT ORANGE (2100 3425);
DISPLAY INVISIBLE (2100 3425);
FORCEPROP 2 LAST CDS_LIB mstr_standard
J 0
(2375 3375);
PAINT ORANGE (2375 3375);
DISPLAY INVISIBLE (2375 3375);
FORCEPROP 1 LAST OFFPAGE TRUE
J 0
(2700 3250);
DISPLAY 0.872340 (2700 3250);
PAINT GREEN (2700 3250);
DISPLAY INVISIBLE (2700 3250);
FORCEPROP 1 LAST COMMENT_BODY TRUE
J 0
(2500 3275);
DISPLAY 0.872340 (2500 3275);
PAINT GREEN (2500 3275);
DISPLAY INVISIBLE (2500 3275);
FORCEADD OFFPAGE..4
(1400 3075);
FORCEPROP 2 LAST $XR0 118 
J 0
(1586 3075);
DISPLAY 0.638298 (1586 3075);
PAINT MONO (1586 3075);
FORCEPROP 2 LAST ROOM SB
J 0
(1150 3125);
DISPLAY 1.361702 (1150 3125);
PAINT ORANGE (1150 3125);
DISPLAY INVISIBLE (1150 3125);
FORCEPROP 2 LAST BOM_COST SB
J 0
(1150 3125);
DISPLAY 1.361702 (1150 3125);
PAINT ORANGE (1150 3125);
DISPLAY INVISIBLE (1150 3125);
FORCEPROP 2 LAST CDS_LIB mstr_standard
J 0
(1400 3075);
PAINT ORANGE (1400 3075);
DISPLAY INVISIBLE (1400 3075);
FORCEPROP 2 LAST PATH I124
J 0
(1600 3125);
DISPLAY 1.021277 (1600 3125);
PAINT ORANGE (1600 3125);
DISPLAY INVISIBLE (1600 3125);
FORCEPROP 1 LAST OFFPAGE TRUE
J 0
(1725 2950);
DISPLAY 0.872340 (1725 2950);
PAINT GREEN (1725 2950);
DISPLAY INVISIBLE (1725 2950);
FORCEPROP 1 LAST COMMENT_BODY TRUE
J 0
(1375 2975);
DISPLAY 0.872340 (1375 2975);
PAINT GREEN (1375 2975);
DISPLAY INVISIBLE (1375 2975);
FORCEADD OFFPAGE..4
(1400 3125);
FORCEPROP 2 LAST $XR0 118 
J 0
(1586 3125);
DISPLAY 0.638298 (1586 3125);
PAINT MONO (1586 3125);
FORCEPROP 2 LAST ROOM SB
J 0
(1150 3175);
DISPLAY 1.361702 (1150 3175);
PAINT ORANGE (1150 3175);
DISPLAY INVISIBLE (1150 3175);
FORCEPROP 2 LAST BOM_COST SB
J 0
(1150 3175);
DISPLAY 1.361702 (1150 3175);
PAINT ORANGE (1150 3175);
DISPLAY INVISIBLE (1150 3175);
FORCEPROP 2 LAST CDS_LIB mstr_standard
J 0
(1400 3125);
PAINT ORANGE (1400 3125);
DISPLAY INVISIBLE (1400 3125);
FORCEPROP 2 LAST PATH I125
J 0
(1600 3175);
DISPLAY 1.021277 (1600 3175);
PAINT ORANGE (1600 3175);
DISPLAY INVISIBLE (1600 3175);
FORCEPROP 1 LAST OFFPAGE TRUE
J 0
(1725 3000);
DISPLAY 0.872340 (1725 3000);
PAINT GREEN (1725 3000);
DISPLAY INVISIBLE (1725 3000);
FORCEPROP 1 LAST COMMENT_BODY TRUE
J 0
(1375 3025);
DISPLAY 0.872340 (1375 3025);
PAINT GREEN (1375 3025);
DISPLAY INVISIBLE (1375 3025);
FORCEADD OFFPAGE..2
(1400 2475);
FORCEPROP 2 LAST $XR0 188 
J 0
(1589 2475);
DISPLAY 0.638298 (1589 2475);
PAINT MONO (1589 2475);
FORCEPROP 2 LAST PATH I126
J 0
(1600 2525);
DISPLAY 1.021277 (1600 2525);
PAINT ORANGE (1600 2525);
DISPLAY INVISIBLE (1600 2525);
FORCEPROP 2 LAST CDS_LIB mstr_standard
J 0
(1400 2475);
PAINT ORANGE (1400 2475);
DISPLAY INVISIBLE (1400 2475);
FORCEPROP 2 LAST ROOM SB
J 0
(1150 2525);
DISPLAY 1.361702 (1150 2525);
PAINT ORANGE (1150 2525);
DISPLAY INVISIBLE (1150 2525);
FORCEPROP 2 LAST BOM_COST SB
J 0
(1150 2525);
DISPLAY 1.361702 (1150 2525);
PAINT ORANGE (1150 2525);
DISPLAY INVISIBLE (1150 2525);
FORCEPROP 1 LAST OFFPAGE TRUE
J 0
(1725 2350);
DISPLAY 0.872340 (1725 2350);
PAINT GREEN (1725 2350);
DISPLAY INVISIBLE (1725 2350);
FORCEPROP 1 LAST COMMENT_BODY TRUE
J 0
(1355 2380);
DISPLAY 0.872340 (1355 2380);
PAINT GREEN (1355 2380);
DISPLAY INVISIBLE (1355 2380);
FORCEADD OFFPAGE..2
(1400 2525);
FORCEPROP 2 LAST $XR0 188 
J 0
(1589 2525);
DISPLAY 0.638298 (1589 2525);
PAINT MONO (1589 2525);
FORCEPROP 2 LAST CDS_LIB mstr_standard
J 0
(1400 2525);
PAINT ORANGE (1400 2525);
DISPLAY INVISIBLE (1400 2525);
FORCEPROP 2 LAST ROOM SB
J 0
(1150 2575);
DISPLAY 1.361702 (1150 2575);
PAINT ORANGE (1150 2575);
DISPLAY INVISIBLE (1150 2575);
FORCEPROP 2 LAST BOM_COST SB
J 0
(1150 2575);
DISPLAY 1.361702 (1150 2575);
PAINT ORANGE (1150 2575);
DISPLAY INVISIBLE (1150 2575);
FORCEPROP 2 LAST PATH I127
J 0
(1600 2575);
DISPLAY 1.021277 (1600 2575);
PAINT ORANGE (1600 2575);
DISPLAY INVISIBLE (1600 2575);
FORCEPROP 1 LAST OFFPAGE TRUE
J 0
(1725 2400);
DISPLAY 0.872340 (1725 2400);
PAINT GREEN (1725 2400);
DISPLAY INVISIBLE (1725 2400);
FORCEPROP 1 LAST COMMENT_BODY TRUE
J 0
(1355 2430);
DISPLAY 0.872340 (1355 2430);
PAINT GREEN (1355 2430);
DISPLAY INVISIBLE (1355 2430);
FORCEADD RES..2
R 1
(-3250 2750);
FORCEPROP 1 LAST PACK_TYPE 0402
J 0
(-2925 2790);
DISPLAY 0.617021 (-2925 2790);
PAINT SKYBLUE (-2925 2790);
FORCEPROP 0 LAST GROUP KR
J 0
(-3338 2687);
DISPLAY 0.638298 (-3338 2687);
PAINT BROWN (-3338 2687);
DISPLAY BOTH (-3338 2687);
FORCEPROP 1 LAST TOLERANCE 1%
J 0
(-3025 2795);
DISPLAY 0.617021 (-3025 2795);
PAINT SKYBLUE (-3025 2795);
FORCEPROP 1 LAST WATTAGE 1/16W
J 0
(-2800 2790);
DISPLAY 0.617021 (-2800 2790);
PAINT SKYBLUE (-2800 2790);
FORCEPROP 1 LASTPIN (-3350 2750) $PN 1
J 0
(-3337 2755);
DISPLAY 0.617021 (-3337 2755);
PAINT ORANGE (-3337 2755);
FORCEPROP 1 LAST LOCATION R1W40
J 0
(-3300 2795);
DISPLAY 0.617021 (-3300 2795);
PAINT AQUA (-3300 2795);
FORCEPROP 1 LAST VALUE 4.75K
J 0
(-3150 2795);
DISPLAY 0.617021 (-3150 2795);
PAINT SKYBLUE (-3150 2795);
FORCEPROP 1 LASTPIN (-3150 2750) $PN 2
J 0
(-3185 2755);
DISPLAY 0.617021 (-3185 2755);
PAINT ORANGE (-3185 2755);
FORCEPROP 1 LAST MATERIAL CHIP
J 0
(-2675 2790);
DISPLAY 0.617021 (-2675 2790);
PAINT SKYBLUE (-2675 2790);
FORCEPROP 1 LAST PART_NUMBER G21796-072
J 0
(-2550 2790);
DISPLAY 0.617021 (-2550 2790);
PAINT BLUE (-2550 2790);
FORCEPROP 2 LAST CDS_LIB mstr_discrete
R 1
J 0
(-3250 2750);
PAINT ORANGE (-3250 2750);
DISPLAY INVISIBLE (-3250 2750);
FORCEPROP 0 LAST ROOM CPU0
R 1
J 0
(-3475 2800);
DISPLAY 1.021277 (-3475 2800);
PAINT ORANGE (-3475 2800);
DISPLAY INVISIBLE (-3475 2800);
FORCEPROP 2 LAST SEC 1
R 1
J 0
(-3475 2800);
DISPLAY 0.680851 (-3475 2800);
PAINT MONO (-3475 2800);
DISPLAY INVISIBLE (-3475 2800);
FORCEPROP 2 LAST SEC_TYPE 0402
R 1
J 0
(-3475 2800);
DISPLAY 1.021277 (-3475 2800);
PAINT ORANGE (-3475 2800);
DISPLAY INVISIBLE (-3475 2800);
FORCEPROP 1 LAST PATH I128
R 1
J 0
(-3425 2800);
DISPLAY 0.978723 (-3425 2800);
PAINT WHITE (-3425 2800);
DISPLAY INVISIBLE (-3425 2800);
FORCEPROP 2 LAST CDS_LOCATION R1W40
R 1
J 0
(-3375 2795);
DISPLAY 0.617021 (-3375 2795);
PAINT AQUA (-3375 2795);
DISPLAY INVISIBLE (-3375 2795);
FORCEADD RES..2
R 1
(-3250 2600);
FORCEPROP 0 LAST GROUP KR
J 0
(-3338 2537);
DISPLAY 0.638298 (-3338 2537);
PAINT BROWN (-3338 2537);
DISPLAY BOTH (-3338 2537);
FORCEPROP 0 LAST POP NOPOP
J 0
(-3125 2600);
DISPLAY 0.638298 (-3125 2600);
PAINT RED (-3125 2600);
FORCEPROP 1 LAST TOLERANCE 1%
J 0
(-3025 2645);
DISPLAY 0.617021 (-3025 2645);
PAINT SKYBLUE (-3025 2645);
FORCEPROP 1 LAST PACK_TYPE 0402
J 0
(-2925 2640);
DISPLAY 0.617021 (-2925 2640);
PAINT SKYBLUE (-2925 2640);
FORCEPROP 1 LAST WATTAGE 1/16W
J 0
(-2800 2640);
DISPLAY 0.617021 (-2800 2640);
PAINT SKYBLUE (-2800 2640);
FORCEPROP 1 LAST VALUE 4.75K
J 0
(-3150 2645);
DISPLAY 0.617021 (-3150 2645);
PAINT SKYBLUE (-3150 2645);
FORCEPROP 1 LASTPIN (-3150 2600) $PN 2
J 0
(-3185 2605);
DISPLAY 0.617021 (-3185 2605);
PAINT ORANGE (-3185 2605);
FORCEPROP 1 LAST LOCATION R1W41
J 0
(-3300 2645);
DISPLAY 0.617021 (-3300 2645);
PAINT AQUA (-3300 2645);
FORCEPROP 1 LASTPIN (-3350 2600) $PN 1
J 0
(-3337 2605);
DISPLAY 0.617021 (-3337 2605);
PAINT ORANGE (-3337 2605);
FORCEPROP 1 LAST PART_NUMBER G21796-072
J 0
(-2550 2640);
DISPLAY 0.617021 (-2550 2640);
PAINT BLUE (-2550 2640);
FORCEPROP 1 LAST MATERIAL CHIP
J 0
(-2675 2640);
DISPLAY 0.617021 (-2675 2640);
PAINT SKYBLUE (-2675 2640);
FORCEPROP 2 LAST CDS_LIB mstr_discrete
R 1
J 0
(-3250 2600);
PAINT ORANGE (-3250 2600);
DISPLAY INVISIBLE (-3250 2600);
FORCEPROP 0 LAST ROOM CPU0
R 1
J 0
(-3475 2650);
DISPLAY 1.021277 (-3475 2650);
PAINT ORANGE (-3475 2650);
DISPLAY INVISIBLE (-3475 2650);
FORCEPROP 2 LAST SEC 1
R 1
J 0
(-3475 2650);
DISPLAY 0.680851 (-3475 2650);
PAINT MONO (-3475 2650);
DISPLAY INVISIBLE (-3475 2650);
FORCEPROP 2 LAST SEC_TYPE 0402
R 1
J 0
(-3475 2650);
DISPLAY 1.021277 (-3475 2650);
PAINT ORANGE (-3475 2650);
DISPLAY INVISIBLE (-3475 2650);
FORCEPROP 2 LAST CDS_LOCATION R1W41
R 1
J 0
(-3375 2645);
DISPLAY 0.617021 (-3375 2645);
PAINT AQUA (-3375 2645);
DISPLAY INVISIBLE (-3375 2645);
FORCEPROP 1 LAST PATH I129
R 1
J 0
(-3425 2650);
DISPLAY 0.978723 (-3425 2650);
PAINT WHITE (-3425 2650);
DISPLAY INVISIBLE (-3425 2650);
FORCEADD OFFPAGE..2
(1400 2825);
FORCEPROP 2 LAST $XR0 188 
J 0
(1589 2825);
DISPLAY 0.638298 (1589 2825);
PAINT MONO (1589 2825);
FORCEPROP 2 LAST PATH I13
J 0
(1600 2875);
DISPLAY 1.021277 (1600 2875);
PAINT ORANGE (1600 2875);
DISPLAY INVISIBLE (1600 2875);
FORCEPROP 2 LAST BOM_COST SB
J 0
(1150 2875);
DISPLAY 1.361702 (1150 2875);
PAINT ORANGE (1150 2875);
DISPLAY INVISIBLE (1150 2875);
FORCEPROP 2 LAST ROOM SB
J 0
(1150 2875);
DISPLAY 1.361702 (1150 2875);
PAINT ORANGE (1150 2875);
DISPLAY INVISIBLE (1150 2875);
FORCEPROP 2 LAST CDS_LIB mstr_standard
J 0
(1400 2825);
PAINT ORANGE (1400 2825);
DISPLAY INVISIBLE (1400 2825);
FORCEPROP 1 LAST OFFPAGE TRUE
J 0
(1725 2700);
DISPLAY 0.872340 (1725 2700);
PAINT GREEN (1725 2700);
DISPLAY INVISIBLE (1725 2700);
FORCEPROP 1 LAST COMMENT_BODY TRUE
J 0
(1355 2730);
DISPLAY 0.872340 (1355 2730);
PAINT GREEN (1355 2730);
DISPLAY INVISIBLE (1355 2730);
FORCEADD GND..1
(-3400 2525);
FORCEPROP 3 LASTPIN (-3400 2575) SIG_NAME GND\g
J 0
(-3390 2585);
DISPLAY 0.659574 (-3390 2585);
PAINT MONO (-3390 2585);
DISPLAY INVISIBLE (-3390 2585);
FORCEPROP 1 LAST PATH I130
J 0
(-3325 2525);
DISPLAY 0.872340 (-3325 2525);
PAINT AQUA (-3325 2525);
DISPLAY INVISIBLE (-3325 2525);
FORCEPROP 1 LAST VOLTAGE 0
J 0
(-3425 2600);
DISPLAY 1.021277 (-3425 2600);
PAINT SKYBLUE (-3425 2600);
DISPLAY INVISIBLE (-3425 2600);
FORCEPROP 2 LAST CDS_LIB mstr_symbols
J 0
(-3400 2525);
PAINT ORANGE (-3400 2525);
DISPLAY INVISIBLE (-3400 2525);
FORCEPROP 1 LAST SIZE 1B
J 0
(-3325 2475);
DISPLAY 0.872340 (-3325 2475);
PAINT GREEN (-3325 2475);
DISPLAY INVISIBLE (-3325 2475);
FORCEPROP 1 LAST BODY_TYPE PLUMBING
J 0
(-3445 2482);
DISPLAY 0.340426 (-3445 2482);
PAINT GREEN (-3445 2482);
DISPLAY INVISIBLE (-3445 2482);
FORCEPROP 1 LAST HDL_POWER GND
J 0
(-3400 2675);
DISPLAY 0.872340 (-3400 2675);
PAINT GREEN (-3400 2675);
DISPLAY INVISIBLE (-3400 2675);
FORCEADD RES..2
R 1
(-3250 2350);
FORCEPROP 1 LAST PACK_TYPE 0402
J 0
(-2925 2390);
DISPLAY 0.617021 (-2925 2390);
PAINT SKYBLUE (-2925 2390);
FORCEPROP 1 LAST LOCATION R1W42
J 0
(-3300 2395);
DISPLAY 0.617021 (-3300 2395);
PAINT AQUA (-3300 2395);
FORCEPROP 1 LASTPIN (-3150 2350) $PN 2
J 0
(-3185 2355);
DISPLAY 0.617021 (-3185 2355);
PAINT ORANGE (-3185 2355);
FORCEPROP 1 LAST MATERIAL CHIP
J 0
(-2675 2390);
DISPLAY 0.617021 (-2675 2390);
PAINT SKYBLUE (-2675 2390);
FORCEPROP 1 LAST TOLERANCE 1%
J 0
(-3025 2395);
DISPLAY 0.617021 (-3025 2395);
PAINT SKYBLUE (-3025 2395);
FORCEPROP 1 LASTPIN (-3350 2350) $PN 1
J 0
(-3337 2355);
DISPLAY 0.617021 (-3337 2355);
PAINT ORANGE (-3337 2355);
FORCEPROP 1 LAST VALUE 4.75K
J 0
(-3150 2395);
DISPLAY 0.617021 (-3150 2395);
PAINT SKYBLUE (-3150 2395);
FORCEPROP 1 LAST WATTAGE 1/16W
J 0
(-2800 2390);
DISPLAY 0.617021 (-2800 2390);
PAINT SKYBLUE (-2800 2390);
FORCEPROP 1 LAST PART_NUMBER G21796-072
J 0
(-2550 2390);
DISPLAY 0.617021 (-2550 2390);
PAINT BLUE (-2550 2390);
FORCEPROP 2 LAST CDS_LIB mstr_discrete
R 1
J 0
(-3250 2350);
PAINT ORANGE (-3250 2350);
DISPLAY INVISIBLE (-3250 2350);
FORCEPROP 0 LAST ROOM CPU0
R 1
J 0
(-3475 2400);
DISPLAY 1.021277 (-3475 2400);
PAINT ORANGE (-3475 2400);
DISPLAY INVISIBLE (-3475 2400);
FORCEPROP 2 LAST SEC 1
R 1
J 0
(-3475 2400);
DISPLAY 0.680851 (-3475 2400);
PAINT MONO (-3475 2400);
DISPLAY INVISIBLE (-3475 2400);
FORCEPROP 2 LAST SEC_TYPE 0402
R 1
J 0
(-3475 2400);
DISPLAY 1.021277 (-3475 2400);
PAINT ORANGE (-3475 2400);
DISPLAY INVISIBLE (-3475 2400);
FORCEPROP 1 LAST PATH I131
R 1
J 0
(-3425 2400);
DISPLAY 0.978723 (-3425 2400);
PAINT WHITE (-3425 2400);
DISPLAY INVISIBLE (-3425 2400);
FORCEPROP 2 LAST CDS_LOCATION R1W42
R 1
J 0
(-3375 2395);
DISPLAY 0.617021 (-3375 2395);
PAINT AQUA (-3375 2395);
DISPLAY INVISIBLE (-3375 2395);
FORCEADD RES..2
R 1
(-3250 2200);
FORCEPROP 1 LAST PACK_TYPE 0402
J 0
(-2925 2240);
DISPLAY 0.617021 (-2925 2240);
PAINT SKYBLUE (-2925 2240);
FORCEPROP 1 LAST VALUE 4.75K
J 0
(-3150 2245);
DISPLAY 0.617021 (-3150 2245);
PAINT SKYBLUE (-3150 2245);
FORCEPROP 1 LASTPIN (-3350 2200) $PN 1
J 0
(-3337 2205);
DISPLAY 0.617021 (-3337 2205);
PAINT ORANGE (-3337 2205);
FORCEPROP 1 LASTPIN (-3150 2200) $PN 2
J 0
(-3185 2205);
DISPLAY 0.617021 (-3185 2205);
PAINT ORANGE (-3185 2205);
FORCEPROP 1 LAST LOCATION R1W43
J 0
(-3300 2245);
DISPLAY 0.617021 (-3300 2245);
PAINT AQUA (-3300 2245);
FORCEPROP 1 LAST TOLERANCE 1%
J 0
(-3025 2245);
DISPLAY 0.617021 (-3025 2245);
PAINT SKYBLUE (-3025 2245);
FORCEPROP 1 LAST WATTAGE 1/16W
J 0
(-2800 2240);
DISPLAY 0.617021 (-2800 2240);
PAINT SKYBLUE (-2800 2240);
FORCEPROP 1 LAST MATERIAL CHIP
J 0
(-2675 2240);
DISPLAY 0.617021 (-2675 2240);
PAINT SKYBLUE (-2675 2240);
FORCEPROP 1 LAST PART_NUMBER G21796-072
J 0
(-2550 2240);
DISPLAY 0.617021 (-2550 2240);
PAINT BLUE (-2550 2240);
FORCEPROP 2 LAST SEC_TYPE 0402
R 1
J 0
(-3475 2250);
DISPLAY 1.021277 (-3475 2250);
PAINT ORANGE (-3475 2250);
DISPLAY INVISIBLE (-3475 2250);
FORCEPROP 2 LAST SEC 1
R 1
J 0
(-3475 2250);
DISPLAY 0.680851 (-3475 2250);
PAINT MONO (-3475 2250);
DISPLAY INVISIBLE (-3475 2250);
FORCEPROP 0 LAST ROOM CPU0
R 1
J 0
(-3475 2250);
DISPLAY 1.021277 (-3475 2250);
PAINT ORANGE (-3475 2250);
DISPLAY INVISIBLE (-3475 2250);
FORCEPROP 2 LAST CDS_LIB mstr_discrete
R 1
J 0
(-3250 2200);
PAINT ORANGE (-3250 2200);
DISPLAY INVISIBLE (-3250 2200);
FORCEPROP 1 LAST PATH I132
R 1
J 0
(-3425 2250);
DISPLAY 0.978723 (-3425 2250);
PAINT WHITE (-3425 2250);
DISPLAY INVISIBLE (-3425 2250);
FORCEPROP 2 LAST CDS_LOCATION R1W43
R 1
J 0
(-3375 2245);
DISPLAY 0.617021 (-3375 2245);
PAINT AQUA (-3375 2245);
DISPLAY INVISIBLE (-3375 2245);
FORCEADD RES..2
R 1
(-3250 2050);
FORCEPROP 1 LAST WATTAGE 1/16W
J 0
(-2800 2090);
DISPLAY 0.617021 (-2800 2090);
PAINT SKYBLUE (-2800 2090);
FORCEPROP 1 LAST PACK_TYPE 0402
J 0
(-2925 2090);
DISPLAY 0.617021 (-2925 2090);
PAINT SKYBLUE (-2925 2090);
FORCEPROP 1 LAST TOLERANCE 1%
J 0
(-3025 2095);
DISPLAY 0.617021 (-3025 2095);
PAINT SKYBLUE (-3025 2095);
FORCEPROP 1 LAST LOCATION R1W44
J 0
(-3300 2095);
DISPLAY 0.617021 (-3300 2095);
PAINT AQUA (-3300 2095);
FORCEPROP 1 LASTPIN (-3350 2050) $PN 1
J 0
(-3337 2055);
DISPLAY 0.617021 (-3337 2055);
PAINT ORANGE (-3337 2055);
FORCEPROP 1 LASTPIN (-3150 2050) $PN 2
J 0
(-3185 2055);
DISPLAY 0.617021 (-3185 2055);
PAINT ORANGE (-3185 2055);
FORCEPROP 1 LAST VALUE 4.75K
J 0
(-3150 2095);
DISPLAY 0.617021 (-3150 2095);
PAINT SKYBLUE (-3150 2095);
FORCEPROP 1 LAST PART_NUMBER G21796-072
J 0
(-2550 2090);
DISPLAY 0.617021 (-2550 2090);
PAINT BLUE (-2550 2090);
FORCEPROP 1 LAST MATERIAL CHIP
J 0
(-2675 2090);
DISPLAY 0.617021 (-2675 2090);
PAINT SKYBLUE (-2675 2090);
FORCEPROP 1 LAST PATH I133
R 1
J 0
(-3425 2100);
DISPLAY 0.978723 (-3425 2100);
PAINT WHITE (-3425 2100);
DISPLAY INVISIBLE (-3425 2100);
FORCEPROP 2 LAST SEC_TYPE 0402
R 1
J 0
(-3475 2100);
DISPLAY 1.021277 (-3475 2100);
PAINT ORANGE (-3475 2100);
DISPLAY INVISIBLE (-3475 2100);
FORCEPROP 2 LAST SEC 1
R 1
J 0
(-3475 2100);
DISPLAY 0.680851 (-3475 2100);
PAINT MONO (-3475 2100);
DISPLAY INVISIBLE (-3475 2100);
FORCEPROP 0 LAST ROOM CPU0
R 1
J 0
(-3475 2100);
DISPLAY 1.021277 (-3475 2100);
PAINT ORANGE (-3475 2100);
DISPLAY INVISIBLE (-3475 2100);
FORCEPROP 2 LAST CDS_LIB mstr_discrete
R 1
J 0
(-3250 2050);
PAINT ORANGE (-3250 2050);
DISPLAY INVISIBLE (-3250 2050);
FORCEPROP 2 LAST CDS_LOCATION R1W44
R 1
J 0
(-3375 2095);
DISPLAY 0.617021 (-3375 2095);
PAINT AQUA (-3375 2095);
DISPLAY INVISIBLE (-3375 2095);
FORCEADD RES..2
R 1
(-3250 1900);
FORCEPROP 1 LAST PART_NUMBER G21796-072
J 0
(-2550 1940);
DISPLAY 0.617021 (-2550 1940);
PAINT BLUE (-2550 1940);
FORCEPROP 1 LAST PACK_TYPE 0402
J 0
(-2925 1940);
DISPLAY 0.617021 (-2925 1940);
PAINT SKYBLUE (-2925 1940);
FORCEPROP 1 LAST MATERIAL CHIP
J 0
(-2675 1940);
DISPLAY 0.617021 (-2675 1940);
PAINT SKYBLUE (-2675 1940);
FORCEPROP 1 LAST LOCATION R1W45
J 0
(-3300 1945);
DISPLAY 0.617021 (-3300 1945);
PAINT AQUA (-3300 1945);
FORCEPROP 1 LASTPIN (-3350 1900) $PN 1
J 0
(-3337 1905);
DISPLAY 0.617021 (-3337 1905);
PAINT ORANGE (-3337 1905);
FORCEPROP 1 LASTPIN (-3150 1900) $PN 2
J 0
(-3185 1905);
DISPLAY 0.617021 (-3185 1905);
PAINT ORANGE (-3185 1905);
FORCEPROP 1 LAST TOLERANCE 1%
J 0
(-3025 1945);
DISPLAY 0.617021 (-3025 1945);
PAINT SKYBLUE (-3025 1945);
FORCEPROP 1 LAST VALUE 4.75K
J 0
(-3150 1945);
DISPLAY 0.617021 (-3150 1945);
PAINT SKYBLUE (-3150 1945);
FORCEPROP 1 LAST WATTAGE 1/16W
J 0
(-2800 1940);
DISPLAY 0.617021 (-2800 1940);
PAINT SKYBLUE (-2800 1940);
FORCEPROP 1 LAST PATH I134
R 1
J 0
(-3425 1950);
DISPLAY 0.978723 (-3425 1950);
PAINT WHITE (-3425 1950);
DISPLAY INVISIBLE (-3425 1950);
FORCEPROP 2 LAST SEC_TYPE 0402
R 1
J 0
(-3475 1950);
DISPLAY 1.021277 (-3475 1950);
PAINT ORANGE (-3475 1950);
DISPLAY INVISIBLE (-3475 1950);
FORCEPROP 2 LAST SEC 1
R 1
J 0
(-3475 1950);
DISPLAY 0.680851 (-3475 1950);
PAINT MONO (-3475 1950);
DISPLAY INVISIBLE (-3475 1950);
FORCEPROP 0 LAST ROOM CPU0
R 1
J 0
(-3475 1950);
DISPLAY 1.021277 (-3475 1950);
PAINT ORANGE (-3475 1950);
DISPLAY INVISIBLE (-3475 1950);
FORCEPROP 2 LAST CDS_LIB mstr_discrete
R 1
J 0
(-3250 1900);
PAINT ORANGE (-3250 1900);
DISPLAY INVISIBLE (-3250 1900);
FORCEPROP 2 LAST CDS_LOCATION R1W45
R 1
J 0
(-3375 1945);
DISPLAY 0.617021 (-3375 1945);
PAINT AQUA (-3375 1945);
DISPLAY INVISIBLE (-3375 1945);
FORCEADD OFFPAGE..2
(1400 2775);
FORCEPROP 2 LAST $XR0 188 
J 0
(1589 2775);
DISPLAY 0.638298 (1589 2775);
PAINT MONO (1589 2775);
FORCEPROP 2 LAST PATH I14
J 0
(1600 2825);
DISPLAY 1.021277 (1600 2825);
PAINT ORANGE (1600 2825);
DISPLAY INVISIBLE (1600 2825);
FORCEPROP 2 LAST BOM_COST SB
J 0
(1150 2825);
DISPLAY 1.361702 (1150 2825);
PAINT ORANGE (1150 2825);
DISPLAY INVISIBLE (1150 2825);
FORCEPROP 2 LAST ROOM SB
J 0
(1150 2825);
DISPLAY 1.361702 (1150 2825);
PAINT ORANGE (1150 2825);
DISPLAY INVISIBLE (1150 2825);
FORCEPROP 2 LAST CDS_LIB mstr_standard
J 0
(1400 2775);
PAINT ORANGE (1400 2775);
DISPLAY INVISIBLE (1400 2775);
FORCEPROP 1 LAST OFFPAGE TRUE
J 0
(1725 2650);
DISPLAY 0.872340 (1725 2650);
PAINT GREEN (1725 2650);
DISPLAY INVISIBLE (1725 2650);
FORCEPROP 1 LAST COMMENT_BODY TRUE
J 0
(1355 2680);
DISPLAY 0.872340 (1355 2680);
PAINT GREEN (1355 2680);
DISPLAY INVISIBLE (1355 2680);
FORCEADD OFFPAGE..4
(1400 2675);
FORCEPROP 2 LAST $XR0 120 
J 0
(1586 2675);
DISPLAY 0.638298 (1586 2675);
PAINT MONO (1586 2675);
FORCEPROP 2 LAST BOM_COST SB
J 0
(1150 2725);
DISPLAY 1.361702 (1150 2725);
PAINT ORANGE (1150 2725);
DISPLAY INVISIBLE (1150 2725);
FORCEPROP 2 LAST ROOM SB
J 0
(1150 2725);
DISPLAY 1.361702 (1150 2725);
PAINT ORANGE (1150 2725);
DISPLAY INVISIBLE (1150 2725);
FORCEPROP 2 LAST CDS_LIB mstr_standard
J 0
(1400 2675);
PAINT ORANGE (1400 2675);
DISPLAY INVISIBLE (1400 2675);
FORCEPROP 2 LAST PATH I15
J 0
(1750 2725);
DISPLAY 1.021277 (1750 2725);
PAINT ORANGE (1750 2725);
DISPLAY INVISIBLE (1750 2725);
FORCEPROP 1 LAST OFFPAGE TRUE
J 0
(1725 2550);
DISPLAY 0.872340 (1725 2550);
PAINT GREEN (1725 2550);
DISPLAY INVISIBLE (1725 2550);
FORCEPROP 1 LAST COMMENT_BODY TRUE
J 0
(1375 2575);
DISPLAY 0.872340 (1375 2575);
PAINT GREEN (1375 2575);
DISPLAY INVISIBLE (1375 2575);
FORCEADD OFFPAGE..4
(1400 2625);
FORCEPROP 2 LAST $XR0 120 
J 0
(1586 2625);
DISPLAY 0.638298 (1586 2625);
PAINT MONO (1586 2625);
FORCEPROP 2 LAST BOM_COST SB
J 0
(1150 2675);
DISPLAY 1.361702 (1150 2675);
PAINT ORANGE (1150 2675);
DISPLAY INVISIBLE (1150 2675);
FORCEPROP 2 LAST ROOM SB
J 0
(1150 2675);
DISPLAY 1.361702 (1150 2675);
PAINT ORANGE (1150 2675);
DISPLAY INVISIBLE (1150 2675);
FORCEPROP 2 LAST CDS_LIB mstr_standard
J 0
(1400 2625);
PAINT ORANGE (1400 2625);
DISPLAY INVISIBLE (1400 2625);
FORCEPROP 2 LAST PATH I16
J 0
(1600 2675);
DISPLAY 1.021277 (1600 2675);
PAINT ORANGE (1600 2675);
DISPLAY INVISIBLE (1600 2675);
FORCEPROP 1 LAST OFFPAGE TRUE
J 0
(1725 2500);
DISPLAY 0.872340 (1725 2500);
PAINT GREEN (1725 2500);
DISPLAY INVISIBLE (1725 2500);
FORCEPROP 1 LAST COMMENT_BODY TRUE
J 0
(1375 2525);
DISPLAY 0.872340 (1375 2525);
PAINT GREEN (1375 2525);
DISPLAY INVISIBLE (1375 2525);
FORCEADD CAP_A..1
(3300 1300);
FORCEPROP 1 LASTPIN (3300 1400) $PN 1
J 0
(3310 1380);
DISPLAY 0.617021 (3310 1380);
PAINT WHITE (3310 1380);
FORCEPROP 1 LAST PACK_TYPE 0402V
J 0
(3350 1100);
DISPLAY 0.617021 (3350 1100);
PAINT SKYBLUE (3350 1100);
FORCEPROP 1 LAST LOCATION C2R15
J 0
(3350 1400);
DISPLAY 0.617021 (3350 1400);
PAINT AQUA (3350 1400);
FORCEPROP 1 LAST VALUE 0.1UF
J 0
(3350 1350);
DISPLAY 0.617021 (3350 1350);
PAINT SKYBLUE (3350 1350);
FORCEPROP 1 LAST VOLTAGE 16V
J 0
(3350 1300);
DISPLAY 0.617021 (3350 1300);
PAINT SKYBLUE (3350 1300);
FORCEPROP 1 LAST TOLERANCE 10%
J 0
(3350 1250);
DISPLAY 0.617021 (3350 1250);
PAINT SKYBLUE (3350 1250);
FORCEPROP 1 LAST MATERIAL X7R
J 0
(3350 1200);
DISPLAY 0.617021 (3350 1200);
PAINT SKYBLUE (3350 1200);
FORCEPROP 1 LAST PART_NUMBER A36096-030
J 0
(3350 1150);
DISPLAY 0.617021 (3350 1150);
PAINT BLUE (3350 1150);
FORCEPROP 1 LASTPIN (3300 1200) $PN 2
J 0
(3310 1180);
DISPLAY 0.617021 (3310 1180);
PAINT WHITE (3310 1180);
FORCEPROP 2 LAST SEC 1
J 0
(3350 1450);
DISPLAY 0.680851 (3350 1450);
PAINT MONO (3350 1450);
DISPLAY INVISIBLE (3350 1450);
FORCEPROP 2 LAST SEC_TYPE 0402V
J 0
(3350 1500);
DISPLAY 1.021277 (3350 1500);
PAINT ORANGE (3350 1500);
DISPLAY INVISIBLE (3350 1500);
FORCEPROP 2 LAST CDS_SEC 1
J 0
(3350 1450);
PAINT ORANGE (3350 1450);
DISPLAY INVISIBLE (3350 1450);
FORCEPROP 2 LAST CDS_LIB dev_discrete
J 0
(3300 1300);
PAINT ORANGE (3300 1300);
DISPLAY INVISIBLE (3300 1300);
FORCEPROP 2 LAST BOM_COST IO_MODULE
J 0
(3300 1300);
DISPLAY 0.744681 (3300 1300);
PAINT MONO (3300 1300);
DISPLAY INVISIBLE (3300 1300);
FORCEPROP 2 LAST ROOM IO_MODULE
J 1
(3350 1450);
DISPLAY 0.744681 (3350 1450);
PAINT ORANGE (3350 1450);
DISPLAY INVISIBLE (3350 1450);
FORCEPROP 1 LAST PATH I2
J 0
(3350 1450);
DISPLAY 0.978723 (3350 1450);
PAINT WHITE (3350 1450);
DISPLAY INVISIBLE (3350 1450);
FORCEADD CAP_A..1
(2400 1300);
FORCEPROP 1 LAST MATERIAL X7R
J 0
(2450 1200);
DISPLAY 0.617021 (2450 1200);
PAINT SKYBLUE (2450 1200);
FORCEPROP 1 LAST PART_NUMBER A36096-030
J 0
(2450 1150);
DISPLAY 0.617021 (2450 1150);
PAINT BLUE (2450 1150);
FORCEPROP 1 LAST PACK_TYPE 0402V
J 0
(2450 1100);
DISPLAY 0.617021 (2450 1100);
PAINT SKYBLUE (2450 1100);
FORCEPROP 1 LAST TOLERANCE 10%
J 0
(2450 1250);
DISPLAY 0.617021 (2450 1250);
PAINT SKYBLUE (2450 1250);
FORCEPROP 1 LAST LOCATION C2P11
J 0
(2450 1400);
DISPLAY 0.617021 (2450 1400);
PAINT AQUA (2450 1400);
FORCEPROP 1 LAST VALUE 0.1UF
J 0
(2450 1350);
DISPLAY 0.617021 (2450 1350);
PAINT SKYBLUE (2450 1350);
FORCEPROP 1 LAST VOLTAGE 16V
J 0
(2450 1300);
DISPLAY 0.617021 (2450 1300);
PAINT SKYBLUE (2450 1300);
FORCEPROP 1 LASTPIN (2400 1400) $PN 1
J 0
(2410 1380);
DISPLAY 0.617021 (2410 1380);
PAINT WHITE (2410 1380);
FORCEPROP 1 LASTPIN (2400 1200) $PN 2
J 0
(2410 1180);
DISPLAY 0.617021 (2410 1180);
PAINT WHITE (2410 1180);
FORCEPROP 1 LAST PATH I21
J 0
(2450 1450);
DISPLAY 0.978723 (2450 1450);
PAINT WHITE (2450 1450);
DISPLAY INVISIBLE (2450 1450);
FORCEPROP 2 LAST ROOM IO_MODULE
J 1
(2450 1450);
DISPLAY 0.744681 (2450 1450);
PAINT ORANGE (2450 1450);
DISPLAY INVISIBLE (2450 1450);
FORCEPROP 2 LAST BOM_COST IO_MODULE
J 0
(2400 1300);
DISPLAY 0.744681 (2400 1300);
PAINT MONO (2400 1300);
DISPLAY INVISIBLE (2400 1300);
FORCEPROP 2 LAST CDS_LIB dev_discrete
J 0
(2400 1300);
PAINT ORANGE (2400 1300);
DISPLAY INVISIBLE (2400 1300);
FORCEPROP 2 LAST CDS_SEC 1
J 0
(2450 1450);
PAINT ORANGE (2450 1450);
DISPLAY INVISIBLE (2450 1450);
FORCEPROP 2 LAST SEC_TYPE 0402V
J 0
(2450 1500);
DISPLAY 1.021277 (2450 1500);
PAINT ORANGE (2450 1500);
DISPLAY INVISIBLE (2450 1500);
FORCEPROP 2 LAST SEC 1
J 0
(2450 1450);
DISPLAY 0.680851 (2450 1450);
PAINT MONO (2450 1450);
DISPLAY INVISIBLE (2450 1450);
FORCEADD CAP_A..1
(2050 1300);
FORCEPROP 1 LAST VALUE 0.1UF
J 0
(2100 1350);
DISPLAY 0.617021 (2100 1350);
PAINT SKYBLUE (2100 1350);
FORCEPROP 1 LAST PACK_TYPE 0402V
J 0
(2100 1100);
DISPLAY 0.617021 (2100 1100);
PAINT SKYBLUE (2100 1100);
FORCEPROP 1 LAST PART_NUMBER A36096-030
J 0
(2100 1150);
DISPLAY 0.617021 (2100 1150);
PAINT BLUE (2100 1150);
FORCEPROP 1 LAST MATERIAL X7R
J 0
(2100 1200);
DISPLAY 0.617021 (2100 1200);
PAINT SKYBLUE (2100 1200);
FORCEPROP 1 LAST TOLERANCE 10%
J 0
(2100 1250);
DISPLAY 0.617021 (2100 1250);
PAINT SKYBLUE (2100 1250);
FORCEPROP 1 LAST VOLTAGE 16V
J 0
(2100 1300);
DISPLAY 0.617021 (2100 1300);
PAINT SKYBLUE (2100 1300);
FORCEPROP 1 LAST LOCATION C2P12
J 0
(2100 1400);
DISPLAY 0.617021 (2100 1400);
PAINT AQUA (2100 1400);
FORCEPROP 1 LASTPIN (2050 1400) $PN 1
J 0
(2060 1380);
DISPLAY 0.617021 (2060 1380);
PAINT WHITE (2060 1380);
FORCEPROP 1 LASTPIN (2050 1200) $PN 2
J 0
(2060 1180);
DISPLAY 0.617021 (2060 1180);
PAINT WHITE (2060 1180);
FORCEPROP 1 LAST PATH I23
J 0
(2100 1450);
DISPLAY 0.978723 (2100 1450);
PAINT WHITE (2100 1450);
DISPLAY INVISIBLE (2100 1450);
FORCEPROP 2 LAST ROOM IO_MODULE
J 1
(2100 1450);
DISPLAY 0.744681 (2100 1450);
PAINT ORANGE (2100 1450);
DISPLAY INVISIBLE (2100 1450);
FORCEPROP 2 LAST BOM_COST IO_MODULE
J 0
(2050 1300);
DISPLAY 0.744681 (2050 1300);
PAINT MONO (2050 1300);
DISPLAY INVISIBLE (2050 1300);
FORCEPROP 2 LAST CDS_LIB dev_discrete
J 0
(2050 1300);
PAINT ORANGE (2050 1300);
DISPLAY INVISIBLE (2050 1300);
FORCEPROP 2 LAST CDS_SEC 1
J 0
(2100 1450);
PAINT ORANGE (2100 1450);
DISPLAY INVISIBLE (2100 1450);
FORCEPROP 2 LAST SEC_TYPE 0402V
J 0
(2100 1500);
DISPLAY 1.021277 (2100 1500);
PAINT ORANGE (2100 1500);
DISPLAY INVISIBLE (2100 1500);
FORCEPROP 2 LAST SEC 1
J 0
(2100 1500);
DISPLAY 0.680851 (2100 1500);
PAINT MONO (2100 1500);
DISPLAY INVISIBLE (2100 1500);
FORCEADD GND..1
(650 2000);
FORCEPROP 3 LASTPIN (650 2050) SIG_NAME GND\g
J 0
(660 2060);
DISPLAY 0.659574 (660 2060);
PAINT MONO (660 2060);
DISPLAY INVISIBLE (660 2060);
FORCEPROP 1 LAST VOLTAGE 0
J 0
(625 2075);
DISPLAY 1.021277 (625 2075);
PAINT SKYBLUE (625 2075);
DISPLAY INVISIBLE (625 2075);
FORCEPROP 1 LAST SIZE 1B
J 0
(725 1950);
DISPLAY 0.872340 (725 1950);
PAINT GREEN (725 1950);
DISPLAY INVISIBLE (725 1950);
FORCEPROP 2 LAST CDS_LIB mstr_symbols
J 0
(650 2000);
PAINT ORANGE (650 2000);
DISPLAY INVISIBLE (650 2000);
FORCEPROP 1 LAST PATH I24
J 0
(725 2000);
DISPLAY 0.872340 (725 2000);
PAINT AQUA (725 2000);
DISPLAY INVISIBLE (725 2000);
FORCEPROP 1 LAST BODY_TYPE PLUMBING
J 0
(605 1957);
DISPLAY 0.340426 (605 1957);
PAINT GREEN (605 1957);
DISPLAY INVISIBLE (605 1957);
FORCEPROP 1 LAST HDL_POWER GND
J 0
(650 2150);
DISPLAY 0.872340 (650 2150);
PAINT GREEN (650 2150);
DISPLAY INVISIBLE (650 2150);
FORCEADD CAP_A..1
(1000 1300);
FORCEPROP 1 LAST PART_NUMBER A36096-030
J 0
(1050 1150);
DISPLAY 0.617021 (1050 1150);
PAINT BLUE (1050 1150);
FORCEPROP 1 LAST LOCATION C2R17
J 0
(1050 1400);
DISPLAY 0.617021 (1050 1400);
PAINT AQUA (1050 1400);
FORCEPROP 1 LAST VALUE 0.1UF
J 0
(1050 1350);
DISPLAY 0.617021 (1050 1350);
PAINT SKYBLUE (1050 1350);
FORCEPROP 1 LAST VOLTAGE 16V
J 0
(1050 1300);
DISPLAY 0.617021 (1050 1300);
PAINT SKYBLUE (1050 1300);
FORCEPROP 1 LAST TOLERANCE 10%
J 0
(1050 1250);
DISPLAY 0.617021 (1050 1250);
PAINT SKYBLUE (1050 1250);
FORCEPROP 1 LAST MATERIAL X7R
J 0
(1050 1200);
DISPLAY 0.617021 (1050 1200);
PAINT SKYBLUE (1050 1200);
FORCEPROP 1 LAST PACK_TYPE 0402V
J 0
(1050 1100);
DISPLAY 0.617021 (1050 1100);
PAINT SKYBLUE (1050 1100);
FORCEPROP 1 LASTPIN (1000 1400) $PN 1
J 0
(1010 1380);
DISPLAY 0.617021 (1010 1380);
PAINT WHITE (1010 1380);
FORCEPROP 1 LASTPIN (1000 1200) $PN 2
J 0
(1010 1180);
DISPLAY 0.617021 (1010 1180);
PAINT WHITE (1010 1180);
FORCEPROP 1 LAST PATH I25
J 0
(1050 1450);
DISPLAY 0.978723 (1050 1450);
PAINT WHITE (1050 1450);
DISPLAY INVISIBLE (1050 1450);
FORCEPROP 2 LAST ROOM IO_MODULE
J 1
(1050 1450);
DISPLAY 0.744681 (1050 1450);
PAINT ORANGE (1050 1450);
DISPLAY INVISIBLE (1050 1450);
FORCEPROP 2 LAST BOM_COST IO_MODULE
J 0
(1000 1300);
DISPLAY 0.744681 (1000 1300);
PAINT MONO (1000 1300);
DISPLAY INVISIBLE (1000 1300);
FORCEPROP 2 LAST CDS_LIB dev_discrete
J 0
(1000 1300);
PAINT ORANGE (1000 1300);
DISPLAY INVISIBLE (1000 1300);
FORCEPROP 2 LAST CDS_SEC 1
J 1
(1050 1500);
DISPLAY 0.744681 (1050 1500);
PAINT MONO (1050 1500);
DISPLAY INVISIBLE (1050 1500);
FORCEPROP 2 LAST $SEC 1
J 1
(1050 1500);
DISPLAY 0.744681 (1050 1500);
PAINT MONO (1050 1500);
DISPLAY INVISIBLE (1050 1500);
FORCEADD SCONN64_H87568002_A..1
(150 3025);
FORCEPROP 1 LAST PART_NUMBER H87568-002
J 0
(-100 2075);
DISPLAY 0.617021 (-100 2075);
PAINT BLUE (-100 2075);
FORCEPROP 0 LAST GROUP KR
J 0
(-88 2012);
DISPLAY 0.638298 (-88 2012);
PAINT BROWN (-88 2012);
DISPLAY BOTH (-88 2012);
FORCEPROP 2 LASTPIN (450 3025) $PN 48
J 0
(460 3035);
DISPLAY 0.617021 (460 3035);
PAINT ORANGE (460 3035);
FORCEPROP 1 LAST LOCATION J8E4
J 0
(-100 4075);
DISPLAY 0.617021 (-100 4075);
PAINT AQUA (-100 4075);
FORCEPROP 2 LASTPIN (-150 3775) $PN 1
J 2
(-160 3785);
DISPLAY 0.617021 (-160 3785);
PAINT ORANGE (-160 3785);
FORCEPROP 2 LASTPIN (-150 3525) $PN 6
J 2
(-160 3535);
DISPLAY 0.617021 (-160 3535);
PAINT ORANGE (-160 3535);
FORCEPROP 2 LASTPIN (-150 3175) $PN 13
J 2
(-160 3185);
DISPLAY 0.617021 (-160 3185);
PAINT ORANGE (-160 3185);
FORCEPROP 2 LASTPIN (-150 2525) $PN 26
J 2
(-160 2535);
DISPLAY 0.617021 (-160 2535);
PAINT ORANGE (-160 2535);
FORCEPROP 2 LASTPIN (-150 2475) $PN 27
J 2
(-160 2485);
DISPLAY 0.617021 (-160 2485);
PAINT ORANGE (-160 2485);
FORCEPROP 2 LASTPIN (450 2575) $PN 57
J 0
(460 2585);
DISPLAY 0.617021 (460 2585);
PAINT ORANGE (460 2585);
FORCEPROP 2 LASTPIN (-150 2625) $PN 24
J 2
(-160 2635);
DISPLAY 0.617021 (-160 2635);
PAINT ORANGE (-160 2635);
FORCEPROP 2 LASTPIN (-150 2925) $PN 18
J 2
(-160 2935);
DISPLAY 0.617021 (-160 2935);
PAINT ORANGE (-160 2935);
FORCEPROP 2 LASTPIN (-150 2975) $PN 17
J 2
(-160 2985);
DISPLAY 0.617021 (-160 2985);
PAINT ORANGE (-160 2985);
FORCEPROP 2 LASTPIN (-150 3025) $PN 16
J 2
(-160 3035);
DISPLAY 0.617021 (-160 3035);
PAINT ORANGE (-160 3035);
FORCEPROP 2 LASTPIN (-150 3075) $PN 15
J 2
(-160 3085);
DISPLAY 0.617021 (-160 3085);
PAINT ORANGE (-160 3085);
FORCEPROP 2 LASTPIN (-150 3125) $PN 14
J 2
(-160 3135);
DISPLAY 0.617021 (-160 3135);
PAINT ORANGE (-160 3135);
FORCEPROP 2 LASTPIN (450 3425) $PN 40
J 0
(460 3435);
DISPLAY 0.617021 (460 3435);
PAINT ORANGE (460 3435);
FORCEPROP 2 LASTPIN (450 2925) $PN 50
J 0
(460 2935);
DISPLAY 0.617021 (460 2935);
PAINT ORANGE (460 2935);
FORCEPROP 2 LASTPIN (450 2775) $PN 53
J 0
(460 2785);
DISPLAY 0.617021 (460 2785);
PAINT ORANGE (460 2785);
FORCEPROP 2 LASTPIN (-150 3725) $PN 2
J 2
(-160 3735);
DISPLAY 0.617021 (-160 3735);
PAINT ORANGE (-160 3735);
FORCEPROP 2 LASTPIN (-150 3675) $PN 3
J 2
(-160 3685);
DISPLAY 0.617021 (-160 3685);
PAINT ORANGE (-160 3685);
FORCEPROP 2 LASTPIN (-150 3625) $PN 4
J 2
(-160 3635);
DISPLAY 0.617021 (-160 3635);
PAINT ORANGE (-160 3635);
FORCEPROP 2 LASTPIN (-150 2425) $PN 28
J 2
(-160 2435);
DISPLAY 0.617021 (-160 2435);
PAINT ORANGE (-160 2435);
FORCEPROP 2 LASTPIN (450 3075) $PN 47
J 0
(460 3085);
DISPLAY 0.617021 (460 3085);
PAINT ORANGE (460 3085);
FORCEPROP 2 LASTPIN (450 3125) $PN 46
J 0
(460 3135);
DISPLAY 0.617021 (460 3135);
PAINT ORANGE (460 3135);
FORCEPROP 2 LASTPIN (450 2275) $PN 63
J 0
(460 2285);
DISPLAY 0.617021 (460 2285);
PAINT ORANGE (460 2285);
FORCEPROP 2 LASTPIN (450 3375) $PN 41
J 0
(460 3385);
DISPLAY 0.617021 (460 3385);
PAINT ORANGE (460 3385);
FORCEPROP 2 LASTPIN (450 3475) $PN 39
J 0
(460 3485);
DISPLAY 0.617021 (460 3485);
PAINT ORANGE (460 3485);
FORCEPROP 2 LASTPIN (450 3525) $PN 38
J 0
(460 3535);
DISPLAY 0.617021 (460 3535);
PAINT ORANGE (460 3535);
FORCEPROP 2 LASTPIN (450 3625) $PN 36
J 0
(460 3635);
DISPLAY 0.617021 (460 3635);
PAINT ORANGE (460 3635);
FORCEPROP 2 LASTPIN (450 3575) $PN 37
J 0
(460 3585);
DISPLAY 0.617021 (460 3585);
PAINT ORANGE (460 3585);
FORCEPROP 2 LASTPIN (450 2975) $PN 49
J 0
(460 2985);
DISPLAY 0.617021 (460 2985);
PAINT ORANGE (460 2985);
FORCEPROP 2 LASTPIN (450 2225) $PN 64
J 0
(460 2235);
DISPLAY 0.617021 (460 2235);
PAINT ORANGE (460 2235);
FORCEPROP 2 LASTPIN (-150 3575) $PN 5
J 2
(-160 3585);
DISPLAY 0.617021 (-160 3585);
PAINT ORANGE (-160 3585);
FORCEPROP 2 LASTPIN (-150 3425) $PN 8
J 2
(-160 3435);
DISPLAY 0.617021 (-160 3435);
PAINT ORANGE (-160 3435);
FORCEPROP 2 LASTPIN (-150 3375) $PN 9
J 2
(-160 3385);
DISPLAY 0.617021 (-160 3385);
PAINT ORANGE (-160 3385);
FORCEPROP 2 LASTPIN (-150 3325) $PN 10
J 2
(-160 3335);
DISPLAY 0.617021 (-160 3335);
PAINT ORANGE (-160 3335);
FORCEPROP 2 LASTPIN (-150 3225) $PN 12
J 2
(-160 3235);
DISPLAY 0.617021 (-160 3235);
PAINT ORANGE (-160 3235);
FORCEPROP 2 LASTPIN (-150 2775) $PN 21
J 2
(-160 2785);
DISPLAY 0.617021 (-160 2785);
PAINT ORANGE (-160 2785);
FORCEPROP 2 LASTPIN (-150 2575) $PN 25
J 2
(-160 2585);
DISPLAY 0.617021 (-160 2585);
PAINT ORANGE (-160 2585);
FORCEPROP 2 LASTPIN (-150 2375) $PN 29
J 2
(-160 2385);
DISPLAY 0.617021 (-160 2385);
PAINT ORANGE (-160 2385);
FORCEPROP 2 LASTPIN (-150 2275) $PN 31
J 2
(-160 2285);
DISPLAY 0.617021 (-160 2285);
PAINT ORANGE (-160 2285);
FORCEPROP 2 LASTPIN (-150 2225) $PN 32
J 2
(-160 2235);
DISPLAY 0.617021 (-160 2235);
PAINT ORANGE (-160 2235);
FORCEPROP 2 LASTPIN (450 3325) $PN 42
J 0
(460 3335);
DISPLAY 0.617021 (460 3335);
PAINT ORANGE (460 3335);
FORCEPROP 2 LASTPIN (450 2825) $PN 52
J 0
(460 2835);
DISPLAY 0.617021 (460 2835);
PAINT ORANGE (460 2835);
FORCEPROP 2 LASTPIN (450 2625) $PN 56
J 0
(460 2635);
DISPLAY 0.617021 (460 2635);
PAINT ORANGE (460 2635);
FORCEPROP 2 LASTPIN (450 2525) $PN 58
J 0
(460 2535);
DISPLAY 0.617021 (460 2535);
PAINT ORANGE (460 2535);
FORCEPROP 2 LASTPIN (450 2375) $PN 61
J 0
(460 2385);
DISPLAY 0.617021 (460 2385);
PAINT ORANGE (460 2385);
FORCEPROP 2 LASTPIN (450 2325) $PN 62
J 0
(460 2335);
DISPLAY 0.617021 (460 2335);
PAINT ORANGE (460 2335);
FORCEPROP 2 LASTPIN (-150 2825) $PN 20
J 2
(-160 2835);
DISPLAY 0.617021 (-160 2835);
PAINT ORANGE (-160 2835);
FORCEPROP 2 LASTPIN (-150 3275) $PN 11
J 2
(-160 3285);
DISPLAY 0.617021 (-160 3285);
PAINT ORANGE (-160 3285);
FORCEPROP 2 LASTPIN (-150 3475) $PN 7
J 2
(-160 3485);
DISPLAY 0.617021 (-160 3485);
PAINT ORANGE (-160 3485);
FORCEPROP 2 LASTPIN (450 2725) $PN 54
J 0
(460 2735);
DISPLAY 0.617021 (460 2735);
PAINT ORANGE (460 2735);
FORCEPROP 2 LASTPIN (450 3175) $PN 45
J 0
(460 3185);
DISPLAY 0.617021 (460 3185);
PAINT ORANGE (460 3185);
FORCEPROP 2 LASTPIN (450 2425) $PN 60
J 0
(460 2435);
DISPLAY 0.617021 (460 2435);
PAINT ORANGE (460 2435);
FORCEPROP 2 LASTPIN (-150 2875) $PN 19
J 2
(-160 2885);
DISPLAY 0.617021 (-160 2885);
PAINT ORANGE (-160 2885);
FORCEPROP 2 LASTPIN (-150 2675) $PN 23
J 2
(-160 2685);
DISPLAY 0.617021 (-160 2685);
PAINT ORANGE (-160 2685);
FORCEPROP 2 LASTPIN (450 2675) $PN 55
J 0
(460 2685);
DISPLAY 0.617021 (460 2685);
PAINT ORANGE (460 2685);
FORCEPROP 2 LASTPIN (-150 2725) $PN 22
J 2
(-160 2735);
DISPLAY 0.617021 (-160 2735);
PAINT ORANGE (-160 2735);
FORCEPROP 2 LASTPIN (450 2475) $PN 59
J 0
(460 2485);
DISPLAY 0.617021 (460 2485);
PAINT ORANGE (460 2485);
FORCEPROP 2 LASTPIN (450 3675) $PN 35
J 0
(460 3685);
DISPLAY 0.617021 (460 3685);
PAINT ORANGE (460 3685);
FORCEPROP 2 LASTPIN (450 3725) $PN 34
J 0
(460 3735);
DISPLAY 0.617021 (460 3735);
PAINT ORANGE (460 3735);
FORCEPROP 2 LASTPIN (450 3775) $PN 33
J 0
(460 3785);
DISPLAY 0.617021 (460 3785);
PAINT ORANGE (460 3785);
FORCEPROP 2 LASTPIN (450 2875) $PN 51
J 0
(460 2885);
DISPLAY 0.617021 (460 2885);
PAINT ORANGE (460 2885);
FORCEPROP 2 LASTPIN (450 3275) $PN 43
J 0
(460 3285);
DISPLAY 0.617021 (460 3285);
PAINT ORANGE (460 3285);
FORCEPROP 2 LASTPIN (450 3225) $PN 44
J 0
(460 3235);
DISPLAY 0.617021 (460 3235);
PAINT ORANGE (460 3235);
FORCEPROP 1 LAST MATERIAL CONN
J 0
(-100 4025);
DISPLAY 0.617021 (-100 4025);
PAINT SKYBLUE (-100 4025);
FORCEPROP 2 LASTPIN (-150 2325) $PN 30
J 2
(-160 2335);
DISPLAY 0.617021 (-160 2335);
PAINT ORANGE (-160 2335);
FORCEPROP 0 LAST ROOM IO_MODULE
J 0
(-100 4175);
DISPLAY 1.021277 (-100 4175);
PAINT ORANGE (-100 4175);
DISPLAY INVISIBLE (-100 4175);
FORCEPROP 1 LAST PATH I27
J 0
(150 4025);
PAINT GREEN (150 4025);
DISPLAY INVISIBLE (150 4025);
FORCEPROP 2 LAST SEC 1
J 0
(-100 4125);
DISPLAY 0.680851 (-100 4125);
PAINT MONO (-100 4125);
DISPLAY INVISIBLE (-100 4125);
FORCEPROP 2 LAST SEC_TYPE SMT
J 0
(-100 4125);
DISPLAY 1.021277 (-100 4125);
PAINT ORANGE (-100 4125);
DISPLAY INVISIBLE (-100 4125);
FORCEPROP 2 LAST CDS_LIB mstr_sconn
J 0
(150 3025);
PAINT ORANGE (150 3025);
DISPLAY INVISIBLE (150 3025);
FORCEPROP 1 LAST PACK_TYPE SMT
J 0
(-100 4125);
PAINT SKYBLUE (-100 4125);
DISPLAY INVISIBLE (-100 4125);
FORCEADD OFFPAGE..1
(-1400 3775);
FORCEPROP 2 LAST $XR3 186 
J 0
(-2012 3775);
DISPLAY 0.638298 (-2012 3775);
PAINT MONO (-2012 3775);
FORCEPROP 2 LAST $XR2 91 
J 0
(-1892 3775);
DISPLAY 0.638298 (-1892 3775);
PAINT MONO (-1892 3775);
FORCEPROP 2 LAST $XR1 159 
J 0
(-1802 3775);
DISPLAY 0.638298 (-1802 3775);
PAINT MONO (-1802 3775);
FORCEPROP 2 LAST $XR0 138 
J 0
(-1682 3775);
DISPLAY 0.638298 (-1682 3775);
PAINT MONO (-1682 3775);
FORCEPROP 2 LAST ROOM SB
J 0
(-1650 3825);
DISPLAY 1.361702 (-1650 3825);
PAINT ORANGE (-1650 3825);
DISPLAY INVISIBLE (-1650 3825);
FORCEPROP 2 LAST BOM_COST SB
J 0
(-1650 3825);
DISPLAY 1.361702 (-1650 3825);
PAINT ORANGE (-1650 3825);
DISPLAY INVISIBLE (-1650 3825);
FORCEPROP 2 LAST CDS_LIB mstr_standard
J 0
(-1400 3775);
PAINT ORANGE (-1400 3775);
DISPLAY INVISIBLE (-1400 3775);
FORCEPROP 2 LAST PATH I28
J 0
(-1675 3825);
DISPLAY 1.021277 (-1675 3825);
PAINT ORANGE (-1675 3825);
DISPLAY INVISIBLE (-1675 3825);
FORCEPROP 1 LAST OFFPAGE TRUE
J 0
(-1075 3650);
DISPLAY 0.872340 (-1075 3650);
PAINT GREEN (-1075 3650);
DISPLAY INVISIBLE (-1075 3650);
FORCEPROP 1 LAST COMMENT_BODY TRUE
J 0
(-1275 3675);
DISPLAY 0.872340 (-1275 3675);
PAINT GREEN (-1275 3675);
DISPLAY INVISIBLE (-1275 3675);
FORCEADD OFFPAGE..6
(-1400 3725);
FORCEPROP 2 LAST $XR2 159 
J 0
(-1889 3725);
DISPLAY 0.638298 (-1889 3725);
PAINT MONO (-1889 3725);
FORCEPROP 2 LAST $XR1 138 
J 0
(-1769 3725);
DISPLAY 0.638298 (-1769 3725);
PAINT MONO (-1769 3725);
FORCEPROP 2 LAST $XR0 91 
J 0
(-1649 3725);
DISPLAY 0.638298 (-1649 3725);
PAINT MONO (-1649 3725);
FORCEPROP 2 LAST $XR3 186 
J 0
(-2009 3725);
DISPLAY 0.638298 (-2009 3725);
PAINT MONO (-2009 3725);
FORCEPROP 2 LAST CDS_LIB mstr_standard
J 0
(-1400 3725);
PAINT ORANGE (-1400 3725);
DISPLAY INVISIBLE (-1400 3725);
FORCEPROP 2 LAST BOM_COST SB
J 0
(-1650 3775);
DISPLAY 1.361702 (-1650 3775);
PAINT ORANGE (-1650 3775);
DISPLAY INVISIBLE (-1650 3775);
FORCEPROP 2 LAST ROOM SB
J 0
(-1650 3775);
DISPLAY 1.361702 (-1650 3775);
PAINT ORANGE (-1650 3775);
DISPLAY INVISIBLE (-1650 3775);
FORCEPROP 2 LAST PATH I29
J 0
(-1725 3775);
DISPLAY 1.021277 (-1725 3775);
PAINT ORANGE (-1725 3775);
DISPLAY INVISIBLE (-1725 3775);
FORCEPROP 1 LAST OFFPAGE TRUE
J 0
(-1075 3600);
DISPLAY 0.872340 (-1075 3600);
PAINT GREEN (-1075 3600);
DISPLAY INVISIBLE (-1075 3600);
FORCEPROP 1 LAST COMMENT_BODY TRUE
J 0
(-1300 3650);
DISPLAY 0.872340 (-1300 3650);
PAINT GREEN (-1300 3650);
DISPLAY INVISIBLE (-1300 3650);
FORCEADD CAP_A..1
(2925 1300);
FORCEPROP 1 LAST LOCATION C2R18
J 0
(2975 1400);
DISPLAY 0.617021 (2975 1400);
PAINT AQUA (2975 1400);
FORCEPROP 1 LAST MATERIAL X7R
J 0
(2975 1200);
DISPLAY 0.617021 (2975 1200);
PAINT SKYBLUE (2975 1200);
FORCEPROP 1 LAST PART_NUMBER A36096-030
J 0
(2975 1150);
DISPLAY 0.617021 (2975 1150);
PAINT BLUE (2975 1150);
FORCEPROP 1 LAST PACK_TYPE 0402V
J 0
(2975 1100);
DISPLAY 0.617021 (2975 1100);
PAINT SKYBLUE (2975 1100);
FORCEPROP 1 LAST TOLERANCE 10%
J 0
(2975 1250);
DISPLAY 0.617021 (2975 1250);
PAINT SKYBLUE (2975 1250);
FORCEPROP 1 LAST VOLTAGE 16V
J 0
(2975 1300);
DISPLAY 0.617021 (2975 1300);
PAINT SKYBLUE (2975 1300);
FORCEPROP 1 LAST VALUE 0.1UF
J 0
(2975 1350);
DISPLAY 0.617021 (2975 1350);
PAINT SKYBLUE (2975 1350);
FORCEPROP 1 LASTPIN (2925 1400) $PN 1
J 0
(2935 1380);
DISPLAY 0.617021 (2935 1380);
PAINT WHITE (2935 1380);
FORCEPROP 1 LASTPIN (2925 1200) $PN 2
J 0
(2935 1180);
DISPLAY 0.617021 (2935 1180);
PAINT WHITE (2935 1180);
FORCEPROP 1 LAST PATH I3
J 0
(2975 1450);
DISPLAY 0.978723 (2975 1450);
PAINT WHITE (2975 1450);
DISPLAY INVISIBLE (2975 1450);
FORCEPROP 2 LAST ROOM IO_MODULE
J 1
(2975 1450);
DISPLAY 0.744681 (2975 1450);
PAINT ORANGE (2975 1450);
DISPLAY INVISIBLE (2975 1450);
FORCEPROP 2 LAST BOM_COST IO_MODULE
J 0
(2925 1300);
DISPLAY 0.744681 (2925 1300);
PAINT MONO (2925 1300);
DISPLAY INVISIBLE (2925 1300);
FORCEPROP 2 LAST CDS_LIB dev_discrete
J 0
(2925 1300);
PAINT ORANGE (2925 1300);
DISPLAY INVISIBLE (2925 1300);
FORCEPROP 2 LAST CDS_SEC 1
J 1
(2975 1500);
DISPLAY 0.744681 (2975 1500);
PAINT MONO (2975 1500);
DISPLAY INVISIBLE (2975 1500);
FORCEPROP 2 LAST $SEC 1
J 1
(2975 1500);
DISPLAY 0.744681 (2975 1500);
PAINT MONO (2975 1500);
DISPLAY INVISIBLE (2975 1500);
FORCEADD OFFPAGE..1
(-1400 3425);
FORCEPROP 2 LAST $XR0 120 
J 0
(-1682 3425);
DISPLAY 0.638298 (-1682 3425);
PAINT MONO (-1682 3425);
FORCEPROP 2 LAST CDS_LIB mstr_standard
J 0
(-1400 3425);
PAINT ORANGE (-1400 3425);
DISPLAY INVISIBLE (-1400 3425);
FORCEPROP 2 LAST BOM_COST SB
J 0
(-1650 3475);
DISPLAY 1.361702 (-1650 3475);
PAINT ORANGE (-1650 3475);
DISPLAY INVISIBLE (-1650 3475);
FORCEPROP 2 LAST ROOM SB
J 0
(-1650 3475);
DISPLAY 1.361702 (-1650 3475);
PAINT ORANGE (-1650 3475);
DISPLAY INVISIBLE (-1650 3475);
FORCEPROP 2 LAST PATH I32
J 0
(-1675 3475);
DISPLAY 1.021277 (-1675 3475);
PAINT ORANGE (-1675 3475);
DISPLAY INVISIBLE (-1675 3475);
FORCEPROP 1 LAST OFFPAGE TRUE
J 0
(-1075 3300);
DISPLAY 0.872340 (-1075 3300);
PAINT GREEN (-1075 3300);
DISPLAY INVISIBLE (-1075 3300);
FORCEPROP 1 LAST COMMENT_BODY TRUE
J 0
(-1275 3325);
DISPLAY 0.872340 (-1275 3325);
PAINT GREEN (-1275 3325);
DISPLAY INVISIBLE (-1275 3325);
FORCEADD OFFPAGE..1
(-1400 3375);
FORCEPROP 2 LAST $XR0 120 
J 0
(-1682 3375);
DISPLAY 0.638298 (-1682 3375);
PAINT MONO (-1682 3375);
FORCEPROP 2 LAST CDS_LIB mstr_standard
J 0
(-1400 3375);
PAINT ORANGE (-1400 3375);
DISPLAY INVISIBLE (-1400 3375);
FORCEPROP 2 LAST BOM_COST SB
J 0
(-1650 3425);
DISPLAY 1.361702 (-1650 3425);
PAINT ORANGE (-1650 3425);
DISPLAY INVISIBLE (-1650 3425);
FORCEPROP 2 LAST ROOM SB
J 0
(-1650 3425);
DISPLAY 1.361702 (-1650 3425);
PAINT ORANGE (-1650 3425);
DISPLAY INVISIBLE (-1650 3425);
FORCEPROP 2 LAST PATH I33
J 0
(-1675 3425);
DISPLAY 1.021277 (-1675 3425);
PAINT ORANGE (-1675 3425);
DISPLAY INVISIBLE (-1675 3425);
FORCEPROP 1 LAST OFFPAGE TRUE
J 0
(-1075 3250);
DISPLAY 0.872340 (-1075 3250);
PAINT GREEN (-1075 3250);
DISPLAY INVISIBLE (-1075 3250);
FORCEPROP 1 LAST COMMENT_BODY TRUE
J 0
(-1275 3275);
DISPLAY 0.872340 (-1275 3275);
PAINT GREEN (-1275 3275);
DISPLAY INVISIBLE (-1275 3275);
FORCEADD OFFPAGE..1
(-1400 3075);
FORCEPROP 2 LAST $XR0 120 
J 0
(-1682 3075);
DISPLAY 0.638298 (-1682 3075);
PAINT MONO (-1682 3075);
FORCEPROP 2 LAST CDS_LIB mstr_standard
J 0
(-1400 3075);
PAINT ORANGE (-1400 3075);
DISPLAY INVISIBLE (-1400 3075);
FORCEPROP 2 LAST BOM_COST SB
J 0
(-1650 3125);
DISPLAY 1.361702 (-1650 3125);
PAINT ORANGE (-1650 3125);
DISPLAY INVISIBLE (-1650 3125);
FORCEPROP 2 LAST ROOM SB
J 0
(-1650 3125);
DISPLAY 1.361702 (-1650 3125);
PAINT ORANGE (-1650 3125);
DISPLAY INVISIBLE (-1650 3125);
FORCEPROP 2 LAST PATH I36
J 0
(-1675 3125);
DISPLAY 1.021277 (-1675 3125);
PAINT ORANGE (-1675 3125);
DISPLAY INVISIBLE (-1675 3125);
FORCEPROP 1 LAST OFFPAGE TRUE
J 0
(-1075 2950);
DISPLAY 0.872340 (-1075 2950);
PAINT GREEN (-1075 2950);
DISPLAY INVISIBLE (-1075 2950);
FORCEPROP 1 LAST COMMENT_BODY TRUE
J 0
(-1275 2975);
DISPLAY 0.872340 (-1275 2975);
PAINT GREEN (-1275 2975);
DISPLAY INVISIBLE (-1275 2975);
FORCEADD OFFPAGE..1
(-1400 3125);
FORCEPROP 2 LAST $XR0 120 
J 0
(-1682 3125);
DISPLAY 0.638298 (-1682 3125);
PAINT MONO (-1682 3125);
FORCEPROP 2 LAST CDS_LIB mstr_standard
J 0
(-1400 3125);
PAINT ORANGE (-1400 3125);
DISPLAY INVISIBLE (-1400 3125);
FORCEPROP 2 LAST BOM_COST SB
J 0
(-1650 3175);
DISPLAY 1.361702 (-1650 3175);
PAINT ORANGE (-1650 3175);
DISPLAY INVISIBLE (-1650 3175);
FORCEPROP 2 LAST ROOM SB
J 0
(-1650 3175);
DISPLAY 1.361702 (-1650 3175);
PAINT ORANGE (-1650 3175);
DISPLAY INVISIBLE (-1650 3175);
FORCEPROP 2 LAST PATH I37
J 0
(-1675 3175);
DISPLAY 1.021277 (-1675 3175);
PAINT ORANGE (-1675 3175);
DISPLAY INVISIBLE (-1675 3175);
FORCEPROP 1 LAST OFFPAGE TRUE
J 0
(-1075 3000);
DISPLAY 0.872340 (-1075 3000);
PAINT GREEN (-1075 3000);
DISPLAY INVISIBLE (-1075 3000);
FORCEPROP 1 LAST COMMENT_BODY TRUE
J 0
(-1275 3025);
DISPLAY 0.872340 (-1275 3025);
PAINT GREEN (-1275 3025);
DISPLAY INVISIBLE (-1275 3025);
FORCEADD GND..1
(-475 2000);
FORCEPROP 3 LASTPIN (-475 2050) SIG_NAME GND\g
J 0
(-465 2060);
DISPLAY 0.659574 (-465 2060);
PAINT MONO (-465 2060);
DISPLAY INVISIBLE (-465 2060);
FORCEPROP 1 LAST PATH I39
J 0
(-400 2000);
DISPLAY 0.872340 (-400 2000);
PAINT AQUA (-400 2000);
DISPLAY INVISIBLE (-400 2000);
FORCEPROP 1 LAST HDL_POWER GND
J 0
(-475 2150);
DISPLAY 0.872340 (-475 2150);
PAINT GREEN (-475 2150);
DISPLAY INVISIBLE (-475 2150);
FORCEPROP 1 LAST BODY_TYPE PLUMBING
J 0
(-520 1957);
DISPLAY 0.340426 (-520 1957);
PAINT GREEN (-520 1957);
DISPLAY INVISIBLE (-520 1957);
FORCEPROP 1 LAST SIZE 1B
J 0
(-400 1950);
DISPLAY 0.872340 (-400 1950);
PAINT GREEN (-400 1950);
DISPLAY INVISIBLE (-400 1950);
FORCEPROP 2 LAST CDS_LIB mstr_symbols
J 0
(-475 2000);
PAINT ORANGE (-475 2000);
DISPLAY INVISIBLE (-475 2000);
FORCEPROP 1 LAST VOLTAGE 0
J 0
(-500 2075);
DISPLAY 1.021277 (-500 2075);
PAINT SKYBLUE (-500 2075);
DISPLAY INVISIBLE (-500 2075);
FORCEADD CAP_A..1
(475 1300);
FORCEPROP 1 LAST PART_NUMBER A36096-030
J 0
(525 1150);
DISPLAY 0.617021 (525 1150);
PAINT BLUE (525 1150);
FORCEPROP 1 LASTPIN (475 1200) $PN 2
J 0
(485 1180);
DISPLAY 0.617021 (485 1180);
PAINT WHITE (485 1180);
FORCEPROP 1 LAST PACK_TYPE 0402V
J 0
(525 1100);
DISPLAY 0.617021 (525 1100);
PAINT SKYBLUE (525 1100);
FORCEPROP 1 LAST MATERIAL X7R
J 0
(525 1200);
DISPLAY 0.617021 (525 1200);
PAINT SKYBLUE (525 1200);
FORCEPROP 1 LAST TOLERANCE 10%
J 0
(525 1250);
DISPLAY 0.617021 (525 1250);
PAINT SKYBLUE (525 1250);
FORCEPROP 1 LAST VOLTAGE 16V
J 0
(525 1300);
DISPLAY 0.617021 (525 1300);
PAINT SKYBLUE (525 1300);
FORCEPROP 1 LASTPIN (475 1400) $PN 1
J 0
(485 1380);
DISPLAY 0.617021 (485 1380);
PAINT WHITE (485 1380);
FORCEPROP 1 LAST VALUE 0.1UF
J 0
(525 1350);
DISPLAY 0.617021 (525 1350);
PAINT SKYBLUE (525 1350);
FORCEPROP 1 LAST LOCATION C2R16
J 0
(525 1400);
DISPLAY 0.617021 (525 1400);
PAINT AQUA (525 1400);
FORCEPROP 1 LAST PATH I40
J 0
(525 1450);
DISPLAY 0.978723 (525 1450);
PAINT WHITE (525 1450);
DISPLAY INVISIBLE (525 1450);
FORCEPROP 2 LAST ROOM IO_MODULE
J 1
(525 1450);
DISPLAY 0.744681 (525 1450);
PAINT ORANGE (525 1450);
DISPLAY INVISIBLE (525 1450);
FORCEPROP 2 LAST BOM_COST IO_MODULE
J 0
(475 1300);
DISPLAY 0.744681 (475 1300);
PAINT MONO (475 1300);
DISPLAY INVISIBLE (475 1300);
FORCEPROP 2 LAST CDS_LIB dev_discrete
J 0
(475 1300);
PAINT ORANGE (475 1300);
DISPLAY INVISIBLE (475 1300);
FORCEPROP 2 LAST CDS_SEC 1
J 1
(525 1500);
DISPLAY 0.744681 (525 1500);
PAINT MONO (525 1500);
DISPLAY INVISIBLE (525 1500);
FORCEPROP 2 LAST $SEC 1
J 1
(525 1500);
DISPLAY 0.744681 (525 1500);
PAINT MONO (525 1500);
DISPLAY INVISIBLE (525 1500);
FORCEADD CAP..1
(-75 1300);
FORCEPROP 1 LAST MATERIAL X6S
J 0
(-25 1200);
DISPLAY 0.617021 (-25 1200);
PAINT SKYBLUE (-25 1200);
FORCEPROP 1 LAST PACK_TYPE 1206LF
J 0
(-25 1100);
DISPLAY 0.617021 (-25 1100);
PAINT SKYBLUE (-25 1100);
FORCEPROP 1 LAST PART_NUMBER D38464-005
J 0
(-25 1150);
DISPLAY 0.617021 (-25 1150);
PAINT BLUE (-25 1150);
FORCEPROP 1 LAST TOLERANCE 10%
J 0
(-25 1250);
DISPLAY 0.617021 (-25 1250);
PAINT SKYBLUE (-25 1250);
FORCEPROP 1 LAST VALUE 22UF
J 0
(-25 1350);
DISPLAY 0.617021 (-25 1350);
PAINT SKYBLUE (-25 1350);
FORCEPROP 1 LASTPIN (-75 1200) $PN 2
J 0
(-65 1180);
DISPLAY 0.617021 (-65 1180);
PAINT WHITE (-65 1180);
FORCEPROP 1 LAST LOCATION C2P10
J 0
(-25 1400);
DISPLAY 0.617021 (-25 1400);
PAINT AQUA (-25 1400);
FORCEPROP 1 LASTPIN (-75 1400) $PN 1
J 0
(-65 1380);
DISPLAY 0.617021 (-65 1380);
PAINT WHITE (-65 1380);
FORCEPROP 1 LAST VOLTAGE 16V
J 0
(-25 1300);
DISPLAY 0.617021 (-25 1300);
PAINT SKYBLUE (-25 1300);
FORCEPROP 2 LAST SEC_TYPE 1206LF
J 0
(-25 1500);
DISPLAY 1.021277 (-25 1500);
PAINT ORANGE (-25 1500);
DISPLAY INVISIBLE (-25 1500);
FORCEPROP 2 LAST BOM_COST IO_MODULE
J 0
(-75 1300);
DISPLAY 0.744681 (-75 1300);
PAINT MONO (-75 1300);
DISPLAY INVISIBLE (-75 1300);
FORCEPROP 2 LAST CDS_LIB mstr_discrete
J 1
(-75 1300);
DISPLAY 0.744681 (-75 1300);
PAINT ORANGE (-75 1300);
DISPLAY INVISIBLE (-75 1300);
FORCEPROP 2 LAST SEC 1
J 0
(-25 1500);
DISPLAY 0.680851 (-25 1500);
PAINT MONO (-25 1500);
DISPLAY INVISIBLE (-25 1500);
FORCEPROP 1 LAST PATH I41
J 0
(-25 1450);
DISPLAY 0.978723 (-25 1450);
PAINT WHITE (-25 1450);
DISPLAY INVISIBLE (-25 1450);
FORCEPROP 2 LAST ROOM IO_MODULE
J 1
(-25 1450);
DISPLAY 0.744681 (-25 1450);
PAINT ORANGE (-25 1450);
DISPLAY INVISIBLE (-25 1450);
FORCEADD CAP_A..1
(-525 1300);
FORCEPROP 1 LAST PART_NUMBER A36096-030
J 0
(-475 1150);
DISPLAY 0.617021 (-475 1150);
PAINT BLUE (-475 1150);
FORCEPROP 1 LAST PACK_TYPE 0402V
J 0
(-475 1100);
DISPLAY 0.617021 (-475 1100);
PAINT SKYBLUE (-475 1100);
FORCEPROP 1 LAST TOLERANCE 10%
J 0
(-475 1250);
DISPLAY 0.617021 (-475 1250);
PAINT SKYBLUE (-475 1250);
FORCEPROP 1 LAST VOLTAGE 16V
J 0
(-475 1300);
DISPLAY 0.617021 (-475 1300);
PAINT SKYBLUE (-475 1300);
FORCEPROP 1 LASTPIN (-525 1400) $PN 1
J 0
(-515 1380);
DISPLAY 0.617021 (-515 1380);
PAINT WHITE (-515 1380);
FORCEPROP 1 LASTPIN (-525 1200) $PN 2
J 0
(-515 1180);
DISPLAY 0.617021 (-515 1180);
PAINT WHITE (-515 1180);
FORCEPROP 1 LAST LOCATION C2P16
J 0
(-475 1400);
DISPLAY 0.617021 (-475 1400);
PAINT AQUA (-475 1400);
FORCEPROP 1 LAST VALUE 0.1UF
J 0
(-475 1350);
DISPLAY 0.617021 (-475 1350);
PAINT SKYBLUE (-475 1350);
FORCEPROP 1 LAST MATERIAL X7R
J 0
(-475 1200);
DISPLAY 0.617021 (-475 1200);
PAINT SKYBLUE (-475 1200);
FORCEPROP 1 LAST PATH I53
J 0
(-475 1450);
DISPLAY 0.978723 (-475 1450);
PAINT WHITE (-475 1450);
DISPLAY INVISIBLE (-475 1450);
FORCEPROP 2 LAST ROOM IO_MODULE
J 1
(-475 1450);
DISPLAY 0.744681 (-475 1450);
PAINT ORANGE (-475 1450);
DISPLAY INVISIBLE (-475 1450);
FORCEPROP 2 LAST BOM_COST IO_MODULE
J 0
(-525 1300);
DISPLAY 0.744681 (-525 1300);
PAINT MONO (-525 1300);
DISPLAY INVISIBLE (-525 1300);
FORCEPROP 2 LAST CDS_LIB dev_discrete
J 0
(-525 1300);
PAINT ORANGE (-525 1300);
DISPLAY INVISIBLE (-525 1300);
FORCEPROP 2 LAST CDS_SEC 1
J 1
(-475 1500);
DISPLAY 0.744681 (-475 1500);
PAINT MONO (-475 1500);
DISPLAY INVISIBLE (-475 1500);
FORCEPROP 2 LAST $SEC 1
J 1
(-475 1500);
DISPLAY 0.744681 (-475 1500);
PAINT MONO (-475 1500);
DISPLAY INVISIBLE (-475 1500);
FORCEADD CAP_A..1
(-950 1300);
FORCEPROP 1 LAST PACK_TYPE 0402V
J 0
(-900 1100);
DISPLAY 0.617021 (-900 1100);
PAINT SKYBLUE (-900 1100);
FORCEPROP 1 LAST MATERIAL X7R
J 0
(-900 1200);
DISPLAY 0.617021 (-900 1200);
PAINT SKYBLUE (-900 1200);
FORCEPROP 1 LAST TOLERANCE 10%
J 0
(-900 1250);
DISPLAY 0.617021 (-900 1250);
PAINT SKYBLUE (-900 1250);
FORCEPROP 1 LAST VOLTAGE 16V
J 0
(-900 1300);
DISPLAY 0.617021 (-900 1300);
PAINT SKYBLUE (-900 1300);
FORCEPROP 1 LAST VALUE 0.1UF
J 0
(-900 1350);
DISPLAY 0.617021 (-900 1350);
PAINT SKYBLUE (-900 1350);
FORCEPROP 1 LAST LOCATION C2P15
J 0
(-900 1400);
DISPLAY 0.617021 (-900 1400);
PAINT AQUA (-900 1400);
FORCEPROP 1 LASTPIN (-950 1400) $PN 1
J 0
(-940 1380);
DISPLAY 0.617021 (-940 1380);
PAINT WHITE (-940 1380);
FORCEPROP 1 LASTPIN (-950 1200) $PN 2
J 0
(-940 1180);
DISPLAY 0.617021 (-940 1180);
PAINT WHITE (-940 1180);
FORCEPROP 1 LAST PART_NUMBER A36096-030
J 0
(-900 1150);
DISPLAY 0.617021 (-900 1150);
PAINT BLUE (-900 1150);
FORCEPROP 1 LAST PATH I55
J 0
(-900 1450);
DISPLAY 0.978723 (-900 1450);
PAINT WHITE (-900 1450);
DISPLAY INVISIBLE (-900 1450);
FORCEPROP 2 LAST ROOM IO_MODULE
J 1
(-900 1450);
DISPLAY 0.744681 (-900 1450);
PAINT ORANGE (-900 1450);
DISPLAY INVISIBLE (-900 1450);
FORCEPROP 2 LAST BOM_COST IO_MODULE
J 0
(-950 1300);
DISPLAY 0.744681 (-950 1300);
PAINT MONO (-950 1300);
DISPLAY INVISIBLE (-950 1300);
FORCEPROP 2 LAST CDS_LIB dev_discrete
J 0
(-950 1300);
PAINT ORANGE (-950 1300);
DISPLAY INVISIBLE (-950 1300);
FORCEPROP 2 LAST CDS_SEC 1
J 1
(-900 1500);
DISPLAY 0.744681 (-900 1500);
PAINT MONO (-900 1500);
DISPLAY INVISIBLE (-900 1500);
FORCEPROP 2 LAST $SEC 1
J 1
(-900 1500);
DISPLAY 0.744681 (-900 1500);
PAINT MONO (-900 1500);
DISPLAY INVISIBLE (-900 1500);
FORCEADD CAP_A..1
(-1400 1300);
FORCEPROP 1 LAST VALUE 0.1UF
J 0
(-1350 1350);
DISPLAY 0.617021 (-1350 1350);
PAINT SKYBLUE (-1350 1350);
FORCEPROP 1 LAST VOLTAGE 16V
J 0
(-1350 1300);
DISPLAY 0.617021 (-1350 1300);
PAINT SKYBLUE (-1350 1300);
FORCEPROP 1 LAST TOLERANCE 10%
J 0
(-1350 1250);
DISPLAY 0.617021 (-1350 1250);
PAINT SKYBLUE (-1350 1250);
FORCEPROP 1 LASTPIN (-1400 1200) $PN 2
J 0
(-1390 1180);
DISPLAY 0.617021 (-1390 1180);
PAINT WHITE (-1390 1180);
FORCEPROP 1 LAST LOCATION C2P14
J 0
(-1350 1400);
DISPLAY 0.617021 (-1350 1400);
PAINT AQUA (-1350 1400);
FORCEPROP 1 LASTPIN (-1400 1400) $PN 1
J 0
(-1390 1380);
DISPLAY 0.617021 (-1390 1380);
PAINT WHITE (-1390 1380);
FORCEPROP 1 LAST PACK_TYPE 0402V
J 0
(-1350 1100);
DISPLAY 0.617021 (-1350 1100);
PAINT SKYBLUE (-1350 1100);
FORCEPROP 1 LAST MATERIAL X7R
J 0
(-1350 1200);
DISPLAY 0.617021 (-1350 1200);
PAINT SKYBLUE (-1350 1200);
FORCEPROP 1 LAST PART_NUMBER A36096-030
J 0
(-1350 1150);
DISPLAY 0.617021 (-1350 1150);
PAINT BLUE (-1350 1150);
FORCEPROP 1 LAST PATH I56
J 0
(-1350 1450);
DISPLAY 0.978723 (-1350 1450);
PAINT WHITE (-1350 1450);
DISPLAY INVISIBLE (-1350 1450);
FORCEPROP 2 LAST ROOM IO_MODULE
J 1
(-1350 1450);
DISPLAY 0.744681 (-1350 1450);
PAINT ORANGE (-1350 1450);
DISPLAY INVISIBLE (-1350 1450);
FORCEPROP 2 LAST BOM_COST IO_MODULE
J 0
(-1400 1300);
DISPLAY 0.744681 (-1400 1300);
PAINT MONO (-1400 1300);
DISPLAY INVISIBLE (-1400 1300);
FORCEPROP 2 LAST CDS_LIB dev_discrete
J 0
(-1400 1300);
PAINT ORANGE (-1400 1300);
DISPLAY INVISIBLE (-1400 1300);
FORCEPROP 2 LAST CDS_SEC 1
J 1
(-1350 1500);
DISPLAY 0.744681 (-1350 1500);
PAINT MONO (-1350 1500);
DISPLAY INVISIBLE (-1350 1500);
FORCEPROP 2 LAST $SEC 1
J 1
(-1350 1500);
DISPLAY 0.744681 (-1350 1500);
PAINT MONO (-1350 1500);
DISPLAY INVISIBLE (-1350 1500);
FORCEADD CAP_A..1
(-1825 1300);
FORCEPROP 1 LAST VOLTAGE 16V
J 0
(-1775 1300);
DISPLAY 0.617021 (-1775 1300);
PAINT SKYBLUE (-1775 1300);
FORCEPROP 1 LAST VALUE 0.1UF
J 0
(-1775 1350);
DISPLAY 0.617021 (-1775 1350);
PAINT SKYBLUE (-1775 1350);
FORCEPROP 1 LAST LOCATION C2P13
J 0
(-1775 1400);
DISPLAY 0.617021 (-1775 1400);
PAINT AQUA (-1775 1400);
FORCEPROP 1 LAST PACK_TYPE 0402V
J 0
(-1775 1100);
DISPLAY 0.617021 (-1775 1100);
PAINT SKYBLUE (-1775 1100);
FORCEPROP 1 LAST MATERIAL X7R
J 0
(-1775 1200);
DISPLAY 0.617021 (-1775 1200);
PAINT SKYBLUE (-1775 1200);
FORCEPROP 1 LASTPIN (-1825 1400) $PN 1
J 0
(-1815 1380);
DISPLAY 0.617021 (-1815 1380);
PAINT WHITE (-1815 1380);
FORCEPROP 1 LAST PART_NUMBER A36096-030
J 0
(-1775 1150);
DISPLAY 0.617021 (-1775 1150);
PAINT BLUE (-1775 1150);
FORCEPROP 1 LASTPIN (-1825 1200) $PN 2
J 0
(-1815 1180);
DISPLAY 0.617021 (-1815 1180);
PAINT WHITE (-1815 1180);
FORCEPROP 1 LAST TOLERANCE 10%
J 0
(-1775 1250);
DISPLAY 0.617021 (-1775 1250);
PAINT SKYBLUE (-1775 1250);
FORCEPROP 1 LAST PATH I57
J 0
(-1775 1450);
DISPLAY 0.978723 (-1775 1450);
PAINT WHITE (-1775 1450);
DISPLAY INVISIBLE (-1775 1450);
FORCEPROP 2 LAST ROOM IO_MODULE
J 1
(-1775 1450);
DISPLAY 0.744681 (-1775 1450);
PAINT ORANGE (-1775 1450);
DISPLAY INVISIBLE (-1775 1450);
FORCEPROP 2 LAST BOM_COST IO_MODULE
J 0
(-1825 1300);
DISPLAY 0.744681 (-1825 1300);
PAINT MONO (-1825 1300);
DISPLAY INVISIBLE (-1825 1300);
FORCEPROP 2 LAST CDS_LIB dev_discrete
J 0
(-1825 1300);
PAINT ORANGE (-1825 1300);
DISPLAY INVISIBLE (-1825 1300);
FORCEPROP 2 LAST CDS_SEC 1
J 1
(-1775 1500);
DISPLAY 0.744681 (-1775 1500);
PAINT MONO (-1775 1500);
DISPLAY INVISIBLE (-1775 1500);
FORCEPROP 2 LAST $SEC 1
J 1
(-1775 1500);
DISPLAY 0.744681 (-1775 1500);
PAINT MONO (-1775 1500);
DISPLAY INVISIBLE (-1775 1500);
FORCEADD GND..1
(200 775);
FORCEPROP 3 LASTPIN (200 825) SIG_NAME GND\g
J 0
(210 835);
DISPLAY 0.659574 (210 835);
PAINT MONO (210 835);
DISPLAY INVISIBLE (210 835);
FORCEPROP 1 LAST VOLTAGE 0
J 0
(175 850);
DISPLAY 1.021277 (175 850);
PAINT SKYBLUE (175 850);
DISPLAY INVISIBLE (175 850);
FORCEPROP 1 LAST SIZE 1B
J 0
(275 725);
DISPLAY 0.872340 (275 725);
PAINT GREEN (275 725);
DISPLAY INVISIBLE (275 725);
FORCEPROP 2 LAST CDS_LIB mstr_symbols
J 1
(200 775);
DISPLAY 0.744681 (200 775);
PAINT ORANGE (200 775);
DISPLAY INVISIBLE (200 775);
FORCEPROP 1 LAST PATH I58
J 0
(275 775);
DISPLAY 0.872340 (275 775);
PAINT AQUA (275 775);
DISPLAY INVISIBLE (275 775);
FORCEPROP 1 LAST BODY_TYPE PLUMBING
J 0
(155 732);
DISPLAY 0.340426 (155 732);
PAINT GREEN (155 732);
DISPLAY INVISIBLE (155 732);
FORCEPROP 1 LAST HDL_POWER GND
J 0
(200 925);
DISPLAY 0.872340 (200 925);
PAINT GREEN (200 925);
DISPLAY INVISIBLE (200 925);
FORCEADD P12V_STBY..1
(875 3925);
FORCEPROP 3 LASTPIN (875 3875) SIG_NAME P12V_STBY\g
J 0
(885 3885);
DISPLAY 0.659574 (885 3885);
PAINT MONO (885 3885);
DISPLAY INVISIBLE (885 3885);
FORCEPROP 1 LAST VOLTAGE 12.0V
J 0
(830 3882);
DISPLAY 0.340426 (830 3882);
PAINT SKYBLUE (830 3882);
DISPLAY INVISIBLE (830 3882);
FORCEPROP 2 LAST CDS_LIB mstr_symbols
J 0
(875 3925);
PAINT ORANGE (875 3925);
DISPLAY INVISIBLE (875 3925);
FORCEPROP 1 LAST SIZE 1B
J 0
(920 3947);
DISPLAY 0.340426 (920 3947);
PAINT GREEN (920 3947);
DISPLAY INVISIBLE (920 3947);
FORCEPROP 1 LAST PATH I59
J 0
(920 3927);
DISPLAY 0.340426 (920 3927);
PAINT GREEN (920 3927);
DISPLAY INVISIBLE (920 3927);
FORCEPROP 1 LAST BODY_TYPE PLUMBING
J 0
(830 3882);
DISPLAY 0.340426 (830 3882);
PAINT GREEN (830 3882);
DISPLAY INVISIBLE (830 3882);
FORCEPROP 1 LAST HDL_POWER P12V_STBY
J 0
(575 3800);
DISPLAY 0.872340 (575 3800);
PAINT ORANGE (575 3800);
DISPLAY INVISIBLE (575 3800);
FORCEADD OFFPAGE..4
(1400 3425);
FORCEPROP 2 LAST $XR0 118 
J 0
(1586 3425);
DISPLAY 0.638298 (1586 3425);
PAINT MONO (1586 3425);
FORCEPROP 2 LAST PATH I6
J 0
(1600 3475);
DISPLAY 1.021277 (1600 3475);
PAINT ORANGE (1600 3475);
DISPLAY INVISIBLE (1600 3475);
FORCEPROP 2 LAST CDS_LIB mstr_standard
J 0
(1400 3425);
PAINT ORANGE (1400 3425);
DISPLAY INVISIBLE (1400 3425);
FORCEPROP 2 LAST BOM_COST SB
J 0
(1150 3475);
DISPLAY 1.361702 (1150 3475);
PAINT ORANGE (1150 3475);
DISPLAY INVISIBLE (1150 3475);
FORCEPROP 2 LAST ROOM SB
J 0
(1150 3475);
DISPLAY 1.361702 (1150 3475);
PAINT ORANGE (1150 3475);
DISPLAY INVISIBLE (1150 3475);
FORCEPROP 1 LAST OFFPAGE TRUE
J 0
(1725 3300);
DISPLAY 0.872340 (1725 3300);
PAINT GREEN (1725 3300);
DISPLAY INVISIBLE (1725 3300);
FORCEPROP 1 LAST COMMENT_BODY TRUE
J 0
(1375 3325);
DISPLAY 0.872340 (1375 3325);
PAINT GREEN (1375 3325);
DISPLAY INVISIBLE (1375 3325);
FORCEADD P12V_STBY..1
(2050 1625);
FORCEPROP 3 LASTPIN (2050 1575) SIG_NAME P12V_STBY\g
J 0
(2060 1585);
DISPLAY 0.659574 (2060 1585);
PAINT MONO (2060 1585);
DISPLAY INVISIBLE (2060 1585);
FORCEPROP 1 LAST VOLTAGE 12.0V
J 0
(2005 1582);
DISPLAY 0.340426 (2005 1582);
PAINT SKYBLUE (2005 1582);
DISPLAY INVISIBLE (2005 1582);
FORCEPROP 1 LAST SIZE 1B
J 0
(2095 1647);
DISPLAY 0.340426 (2095 1647);
PAINT GREEN (2095 1647);
DISPLAY INVISIBLE (2095 1647);
FORCEPROP 2 LAST CDS_LIB mstr_symbols
J 0
(2050 1625);
PAINT ORANGE (2050 1625);
DISPLAY INVISIBLE (2050 1625);
FORCEPROP 1 LAST PATH I60
J 0
(2095 1627);
DISPLAY 0.340426 (2095 1627);
PAINT GREEN (2095 1627);
DISPLAY INVISIBLE (2095 1627);
FORCEPROP 1 LAST BODY_TYPE PLUMBING
J 0
(2005 1582);
DISPLAY 0.340426 (2005 1582);
PAINT GREEN (2005 1582);
DISPLAY INVISIBLE (2005 1582);
FORCEPROP 1 LAST HDL_POWER P12V_STBY
J 0
(1750 1500);
DISPLAY 0.872340 (1750 1500);
PAINT ORANGE (1750 1500);
DISPLAY INVISIBLE (1750 1500);
FORCEADD P12V_STBY..1
(850 1625);
FORCEPROP 3 LASTPIN (850 1575) SIG_NAME P12V_STBY\g
J 0
(860 1585);
DISPLAY 0.659574 (860 1585);
PAINT MONO (860 1585);
DISPLAY INVISIBLE (860 1585);
FORCEPROP 1 LAST VOLTAGE 12.0V
J 0
(805 1582);
DISPLAY 0.340426 (805 1582);
PAINT SKYBLUE (805 1582);
DISPLAY INVISIBLE (805 1582);
FORCEPROP 2 LAST CDS_LIB mstr_symbols
J 0
(850 1625);
PAINT ORANGE (850 1625);
DISPLAY INVISIBLE (850 1625);
FORCEPROP 1 LAST SIZE 1B
J 0
(895 1647);
DISPLAY 0.340426 (895 1647);
PAINT GREEN (895 1647);
DISPLAY INVISIBLE (895 1647);
FORCEPROP 1 LAST PATH I61
J 0
(895 1627);
DISPLAY 0.340426 (895 1627);
PAINT GREEN (895 1627);
DISPLAY INVISIBLE (895 1627);
FORCEPROP 1 LAST BODY_TYPE PLUMBING
J 0
(805 1582);
DISPLAY 0.340426 (805 1582);
PAINT GREEN (805 1582);
DISPLAY INVISIBLE (805 1582);
FORCEPROP 1 LAST HDL_POWER P12V_STBY
J 0
(550 1500);
DISPLAY 0.872340 (550 1500);
PAINT ORANGE (550 1500);
DISPLAY INVISIBLE (550 1500);
FORCEADD P12V_STBY..1
(-1100 1625);
FORCEPROP 3 LASTPIN (-1100 1575) SIG_NAME P12V_STBY\g
J 0
(-1090 1585);
DISPLAY 0.659574 (-1090 1585);
PAINT MONO (-1090 1585);
DISPLAY INVISIBLE (-1090 1585);
FORCEPROP 1 LAST VOLTAGE 12.0V
J 0
(-1145 1582);
DISPLAY 0.340426 (-1145 1582);
PAINT SKYBLUE (-1145 1582);
DISPLAY INVISIBLE (-1145 1582);
FORCEPROP 2 LAST CDS_LIB mstr_symbols
J 0
(-1100 1625);
PAINT ORANGE (-1100 1625);
DISPLAY INVISIBLE (-1100 1625);
FORCEPROP 1 LAST SIZE 1B
J 0
(-1055 1647);
DISPLAY 0.340426 (-1055 1647);
PAINT GREEN (-1055 1647);
DISPLAY INVISIBLE (-1055 1647);
FORCEPROP 1 LAST PATH I62
J 0
(-1055 1627);
DISPLAY 0.340426 (-1055 1627);
PAINT GREEN (-1055 1627);
DISPLAY INVISIBLE (-1055 1627);
FORCEPROP 1 LAST BODY_TYPE PLUMBING
J 0
(-1145 1582);
DISPLAY 0.340426 (-1145 1582);
PAINT GREEN (-1145 1582);
DISPLAY INVISIBLE (-1145 1582);
FORCEPROP 1 LAST HDL_POWER P12V_STBY
J 0
(-1400 1500);
DISPLAY 0.872340 (-1400 1500);
PAINT ORANGE (-1400 1500);
DISPLAY INVISIBLE (-1400 1500);
FORCEADD P12V_STBY..1
(3300 1650);
FORCEPROP 3 LASTPIN (3300 1600) SIG_NAME P12V_STBY\g
J 0
(3310 1610);
DISPLAY 0.659574 (3310 1610);
PAINT MONO (3310 1610);
DISPLAY INVISIBLE (3310 1610);
FORCEPROP 1 LAST VOLTAGE 12.0V
J 0
(3255 1607);
DISPLAY 0.340426 (3255 1607);
PAINT SKYBLUE (3255 1607);
DISPLAY INVISIBLE (3255 1607);
FORCEPROP 2 LAST CDS_LIB mstr_symbols
J 0
(3300 1650);
PAINT ORANGE (3300 1650);
DISPLAY INVISIBLE (3300 1650);
FORCEPROP 1 LAST SIZE 1B
J 0
(3345 1672);
DISPLAY 0.340426 (3345 1672);
PAINT GREEN (3345 1672);
DISPLAY INVISIBLE (3345 1672);
FORCEPROP 1 LAST PATH I63
J 0
(3345 1652);
DISPLAY 0.340426 (3345 1652);
PAINT GREEN (3345 1652);
DISPLAY INVISIBLE (3345 1652);
FORCEPROP 1 LAST BODY_TYPE PLUMBING
J 0
(3255 1607);
DISPLAY 0.340426 (3255 1607);
PAINT GREEN (3255 1607);
DISPLAY INVISIBLE (3255 1607);
FORCEPROP 1 LAST HDL_POWER P12V_STBY
J 0
(3000 1525);
DISPLAY 0.872340 (3000 1525);
PAINT ORANGE (3000 1525);
DISPLAY INVISIBLE (3000 1525);
FORCEADD OFFPAGE..4
(1400 3375);
FORCEPROP 2 LAST $XR0 118 
J 0
(1586 3375);
DISPLAY 0.638298 (1586 3375);
PAINT MONO (1586 3375);
FORCEPROP 2 LAST PATH I7
J 0
(1600 3425);
DISPLAY 1.021277 (1600 3425);
PAINT ORANGE (1600 3425);
DISPLAY INVISIBLE (1600 3425);
FORCEPROP 2 LAST CDS_LIB mstr_standard
J 0
(1400 3375);
PAINT ORANGE (1400 3375);
DISPLAY INVISIBLE (1400 3375);
FORCEPROP 2 LAST BOM_COST SB
J 0
(1150 3425);
DISPLAY 1.361702 (1150 3425);
PAINT ORANGE (1150 3425);
DISPLAY INVISIBLE (1150 3425);
FORCEPROP 2 LAST ROOM SB
J 0
(1150 3425);
DISPLAY 1.361702 (1150 3425);
PAINT ORANGE (1150 3425);
DISPLAY INVISIBLE (1150 3425);
FORCEPROP 1 LAST OFFPAGE TRUE
J 0
(1725 3250);
DISPLAY 0.872340 (1725 3250);
PAINT GREEN (1725 3250);
DISPLAY INVISIBLE (1725 3250);
FORCEPROP 1 LAST COMMENT_BODY TRUE
J 0
(1375 3275);
DISPLAY 0.872340 (1375 3275);
PAINT GREEN (1375 3275);
DISPLAY INVISIBLE (1375 3275);
FORCEADD OFFPAGE..2
(3775 2600);
FORCEPROP 2 LAST $XR0 118 
J 0
(3964 2600);
DISPLAY 0.638298 (3964 2600);
PAINT MONO (3964 2600);
FORCEPROP 2 LAST PATH I76
J 0
(3950 2675);
DISPLAY 1.021277 (3950 2675);
PAINT ORANGE (3950 2675);
DISPLAY INVISIBLE (3950 2675);
FORCEPROP 2 LAST CDS_LIB mstr_standard
J 0
(3775 2600);
PAINT ORANGE (3775 2600);
DISPLAY INVISIBLE (3775 2600);
FORCEPROP 1 LAST OFFPAGE TRUE
J 0
(4100 2475);
DISPLAY 0.872340 (4100 2475);
PAINT GREEN (4100 2475);
DISPLAY INVISIBLE (4100 2475);
FORCEPROP 1 LAST COMMENT_BODY TRUE
J 0
(3730 2505);
DISPLAY 0.872340 (3730 2505);
PAINT GREEN (3730 2505);
DISPLAY INVISIBLE (3730 2505);
FORCEADD OFFPAGE..2
(3775 2925);
FORCEPROP 2 LAST $XR0 118 
J 0
(3964 2925);
DISPLAY 0.638298 (3964 2925);
PAINT MONO (3964 2925);
FORCEPROP 2 LAST PATH I79
J 0
(3950 3000);
DISPLAY 1.021277 (3950 3000);
PAINT ORANGE (3950 3000);
DISPLAY INVISIBLE (3950 3000);
FORCEPROP 2 LAST CDS_LIB mstr_standard
J 0
(3775 2925);
PAINT ORANGE (3775 2925);
DISPLAY INVISIBLE (3775 2925);
FORCEPROP 1 LAST OFFPAGE TRUE
J 0
(4100 2800);
DISPLAY 0.872340 (4100 2800);
PAINT GREEN (4100 2800);
DISPLAY INVISIBLE (4100 2800);
FORCEPROP 1 LAST COMMENT_BODY TRUE
J 0
(3730 2830);
DISPLAY 0.872340 (3730 2830);
PAINT GREEN (3730 2830);
DISPLAY INVISIBLE (3730 2830);
FORCEADD OFFPAGE..4
(1400 3275);
FORCEPROP 2 LAST $XR0 120 
J 0
(1586 3275);
DISPLAY 0.638298 (1586 3275);
PAINT MONO (1586 3275);
FORCEPROP 2 LAST BOM_COST SB
J 0
(1150 3325);
DISPLAY 1.361702 (1150 3325);
PAINT ORANGE (1150 3325);
DISPLAY INVISIBLE (1150 3325);
FORCEPROP 2 LAST ROOM SB
J 0
(1150 3325);
DISPLAY 1.361702 (1150 3325);
PAINT ORANGE (1150 3325);
DISPLAY INVISIBLE (1150 3325);
FORCEPROP 2 LAST CDS_LIB mstr_standard
J 0
(1400 3275);
PAINT ORANGE (1400 3275);
DISPLAY INVISIBLE (1400 3275);
FORCEPROP 2 LAST PATH I8
J 0
(1900 3325);
DISPLAY 1.021277 (1900 3325);
PAINT ORANGE (1900 3325);
DISPLAY INVISIBLE (1900 3325);
FORCEPROP 1 LAST OFFPAGE TRUE
J 0
(1725 3150);
DISPLAY 0.872340 (1725 3150);
PAINT GREEN (1725 3150);
DISPLAY INVISIBLE (1725 3150);
FORCEPROP 1 LAST COMMENT_BODY TRUE
J 0
(1375 3175);
DISPLAY 0.872340 (1375 3175);
PAINT GREEN (1375 3175);
DISPLAY INVISIBLE (1375 3175);
FORCEADD CAP_A..2
(3075 2925);
FORCEPROP 1 LAST PART_NUMBER A36096-030
J 1
(3075 2975);
DISPLAY 0.617021 (3075 2975);
PAINT BLUE (3075 2975);
FORCEPROP 1 LASTPIN (2975 2925) $PN 1
J 0
(2965 2940);
DISPLAY 0.617021 (2965 2940);
PAINT ORANGE (2965 2940);
FORCEPROP 1 LASTPIN (3175 2925) $PN 2
J 0
(3160 2940);
DISPLAY 0.617021 (3160 2940);
PAINT ORANGE (3160 2940);
FORCEPROP 1 LAST VOLTAGE 16V
J 0
(3075 2825);
DISPLAY 0.617021 (3075 2825);
PAINT SKYBLUE (3075 2825);
FORCEPROP 1 LAST PACK_TYPE 0402V
J 1
(3275 2825);
DISPLAY 0.617021 (3275 2825);
PAINT SKYBLUE (3275 2825);
FORCEPROP 1 LAST LOCATION C8C15
J 1
(3075 3025);
DISPLAY 0.617021 (3075 3025);
PAINT AQUA (3075 3025);
FORCEPROP 1 LAST MATERIAL X7R
J 0
(3075 2775);
DISPLAY 0.617021 (3075 2775);
PAINT SKYBLUE (3075 2775);
FORCEPROP 1 LAST TOLERANCE 10%
J 2
(3050 2775);
DISPLAY 0.617021 (3050 2775);
PAINT SKYBLUE (3050 2775);
FORCEPROP 1 LAST VALUE 0.1UF
J 2
(3075 2825);
DISPLAY 0.617021 (3075 2825);
PAINT SKYBLUE (3075 2825);
FORCEPROP 2 LAST SEC 1
J 0
(3075 3075);
DISPLAY 0.680851 (3075 3075);
PAINT MONO (3075 3075);
DISPLAY INVISIBLE (3075 3075);
FORCEPROP 2 LAST SEC_TYPE 0402V
J 0
(3075 3175);
DISPLAY 1.021277 (3075 3175);
PAINT ORANGE (3075 3175);
DISPLAY INVISIBLE (3075 3175);
FORCEPROP 2 LAST CDS_SEC 1
J 0
(3075 3075);
PAINT ORANGE (3075 3075);
DISPLAY INVISIBLE (3075 3075);
FORCEPROP 2 LAST CDS_LIB dev_discrete
J 0
(3075 2925);
PAINT ORANGE (3075 2925);
DISPLAY INVISIBLE (3075 2925);
FORCEPROP 1 LAST PATH I82
J 0
(3075 3125);
DISPLAY 0.978723 (3075 3125);
PAINT WHITE (3075 3125);
DISPLAY INVISIBLE (3075 3125);
FORCEADD OFFPAGE..1
(2375 2925);
FORCEPROP 2 LAST $XR0 188 
J 0
(2093 2925);
DISPLAY 0.638298 (2093 2925);
PAINT MONO (2093 2925);
FORCEPROP 2 LAST PATH I85
J 0
(2425 3000);
DISPLAY 1.021277 (2425 3000);
PAINT ORANGE (2425 3000);
DISPLAY INVISIBLE (2425 3000);
FORCEPROP 2 LAST CDS_LIB mstr_standard
J 0
(2375 2925);
PAINT ORANGE (2375 2925);
DISPLAY INVISIBLE (2375 2925);
FORCEPROP 1 LAST OFFPAGE TRUE
J 0
(2700 2800);
DISPLAY 0.872340 (2700 2800);
PAINT GREEN (2700 2800);
DISPLAY INVISIBLE (2700 2800);
FORCEPROP 1 LAST COMMENT_BODY TRUE
J 0
(2500 2825);
DISPLAY 0.872340 (2500 2825);
PAINT GREEN (2500 2825);
DISPLAY INVISIBLE (2500 2825);
FORCEADD CAP_A..2
(3075 2600);
FORCEPROP 1 LAST LOCATION C8C14
J 1
(3075 2700);
DISPLAY 0.617021 (3075 2700);
PAINT AQUA (3075 2700);
FORCEPROP 1 LAST PART_NUMBER A36096-030
J 1
(3075 2650);
DISPLAY 0.617021 (3075 2650);
PAINT BLUE (3075 2650);
FORCEPROP 1 LAST VALUE 0.1UF
J 2
(3075 2500);
DISPLAY 0.617021 (3075 2500);
PAINT SKYBLUE (3075 2500);
FORCEPROP 1 LAST TOLERANCE 10%
J 2
(3050 2450);
DISPLAY 0.617021 (3050 2450);
PAINT SKYBLUE (3050 2450);
FORCEPROP 1 LAST PACK_TYPE 0402V
J 1
(3275 2500);
DISPLAY 0.617021 (3275 2500);
PAINT SKYBLUE (3275 2500);
FORCEPROP 1 LASTPIN (3175 2600) $PN 2
J 0
(3160 2615);
DISPLAY 0.617021 (3160 2615);
PAINT ORANGE (3160 2615);
FORCEPROP 1 LASTPIN (2975 2600) $PN 1
J 0
(2965 2615);
DISPLAY 0.617021 (2965 2615);
PAINT ORANGE (2965 2615);
FORCEPROP 1 LAST MATERIAL X7R
J 0
(3075 2450);
DISPLAY 0.617021 (3075 2450);
PAINT SKYBLUE (3075 2450);
FORCEPROP 1 LAST VOLTAGE 16V
J 0
(3075 2500);
DISPLAY 0.617021 (3075 2500);
PAINT SKYBLUE (3075 2500);
FORCEPROP 2 LAST SEC 1
J 0
(3075 2750);
DISPLAY 0.680851 (3075 2750);
PAINT MONO (3075 2750);
DISPLAY INVISIBLE (3075 2750);
FORCEPROP 2 LAST SEC_TYPE 0402V
J 0
(3075 2850);
DISPLAY 1.021277 (3075 2850);
PAINT ORANGE (3075 2850);
DISPLAY INVISIBLE (3075 2850);
FORCEPROP 2 LAST CDS_SEC 1
J 0
(3075 2750);
PAINT ORANGE (3075 2750);
DISPLAY INVISIBLE (3075 2750);
FORCEPROP 2 LAST CDS_LIB dev_discrete
J 0
(3075 2600);
PAINT ORANGE (3075 2600);
DISPLAY INVISIBLE (3075 2600);
FORCEPROP 1 LAST PATH I86
J 0
(3075 2800);
DISPLAY 0.978723 (3075 2800);
PAINT WHITE (3075 2800);
DISPLAY INVISIBLE (3075 2800);
FORCEADD OFFPAGE..1
(2375 2600);
FORCEPROP 2 LAST $XR0 188 
J 0
(2093 2600);
DISPLAY 0.638298 (2093 2600);
PAINT MONO (2093 2600);
FORCEPROP 2 LAST PATH I87
J 0
(2425 2675);
DISPLAY 1.021277 (2425 2675);
PAINT ORANGE (2425 2675);
DISPLAY INVISIBLE (2425 2675);
FORCEPROP 2 LAST CDS_LIB mstr_standard
J 0
(2375 2600);
PAINT ORANGE (2375 2600);
DISPLAY INVISIBLE (2375 2600);
FORCEPROP 1 LAST OFFPAGE TRUE
J 0
(2700 2475);
DISPLAY 0.872340 (2700 2475);
PAINT GREEN (2700 2475);
DISPLAY INVISIBLE (2700 2475);
FORCEPROP 1 LAST COMMENT_BODY TRUE
J 0
(2500 2500);
DISPLAY 0.872340 (2500 2500);
PAINT GREEN (2500 2500);
DISPLAY INVISIBLE (2500 2500);
FORCEADD RES..1
(-3250 3950);
FORCEPROP 1 LAST PART_NUMBER G21796-112
J 0
(-2550 4000);
DISPLAY 0.617021 (-2550 4000);
PAINT BLUE (-2550 4000);
FORCEPROP 1 LASTPIN (-3350 3950) $PN 1
J 0
(-3338 3962);
DISPLAY 0.617021 (-3338 3962);
PAINT ORANGE (-3338 3962);
FORCEPROP 1 LAST MATERIAL CHIP
J 0
(-2675 4000);
DISPLAY 0.617021 (-2675 4000);
PAINT SKYBLUE (-2675 4000);
FORCEPROP 1 LAST WATTAGE 1/16W
J 2
(-2700 4000);
DISPLAY 0.617021 (-2700 4000);
PAINT SKYBLUE (-2700 4000);
FORCEPROP 1 LAST TOLERANCE 1%
J 0
(-3025 4000);
DISPLAY 0.617021 (-3025 4000);
PAINT SKYBLUE (-3025 4000);
FORCEPROP 1 LAST PACK_TYPE 0402
J 0
(-2925 4000);
DISPLAY 0.617021 (-2925 4000);
PAINT SKYBLUE (-2925 4000);
FORCEPROP 1 LASTPIN (-3150 3950) $PN 2
J 0
(-3188 3962);
DISPLAY 0.617021 (-3188 3962);
PAINT ORANGE (-3188 3962);
FORCEPROP 1 LAST LOCATION R1R18
J 0
(-3300 4000);
DISPLAY 0.617021 (-3300 4000);
PAINT AQUA (-3300 4000);
FORCEPROP 1 LAST VALUE 2.21K
J 2
(-3050 4000);
DISPLAY 0.617021 (-3050 4000);
PAINT SKYBLUE (-3050 4000);
FORCEPROP 1 LAST PATH I88
J 0
(-3300 4100);
DISPLAY 0.978723 (-3300 4100);
PAINT WHITE (-3300 4100);
DISPLAY INVISIBLE (-3300 4100);
FORCEPROP 2 LAST SEC 1
J 0
(-3300 4150);
DISPLAY 0.680851 (-3300 4150);
PAINT MONO (-3300 4150);
DISPLAY INVISIBLE (-3300 4150);
FORCEPROP 2 LAST SEC_TYPE 0402
J 0
(-3300 4150);
DISPLAY 1.021277 (-3300 4150);
PAINT ORANGE (-3300 4150);
DISPLAY INVISIBLE (-3300 4150);
FORCEPROP 2 LAST CDS_LIB mstr_discrete
J 0
(-3250 3950);
PAINT ORANGE (-3250 3950);
DISPLAY INVISIBLE (-3250 3950);
FORCEADD RES..1
(-3250 3800);
FORCEPROP 1 LAST PART_NUMBER G21796-112
J 0
(-2550 3850);
DISPLAY 0.617021 (-2550 3850);
PAINT BLUE (-2550 3850);
FORCEPROP 1 LASTPIN (-3350 3800) $PN 1
J 0
(-3338 3812);
DISPLAY 0.617021 (-3338 3812);
PAINT ORANGE (-3338 3812);
FORCEPROP 1 LAST MATERIAL CHIP
J 0
(-2675 3850);
DISPLAY 0.617021 (-2675 3850);
PAINT SKYBLUE (-2675 3850);
FORCEPROP 1 LAST WATTAGE 1/16W
J 2
(-2700 3850);
DISPLAY 0.617021 (-2700 3850);
PAINT SKYBLUE (-2700 3850);
FORCEPROP 1 LAST PACK_TYPE 0402
J 0
(-2925 3850);
DISPLAY 0.617021 (-2925 3850);
PAINT SKYBLUE (-2925 3850);
FORCEPROP 1 LAST TOLERANCE 1%
J 0
(-3025 3850);
DISPLAY 0.617021 (-3025 3850);
PAINT SKYBLUE (-3025 3850);
FORCEPROP 1 LASTPIN (-3150 3800) $PN 2
J 0
(-3188 3812);
DISPLAY 0.617021 (-3188 3812);
PAINT ORANGE (-3188 3812);
FORCEPROP 1 LAST LOCATION R1R19
J 0
(-3300 3850);
DISPLAY 0.617021 (-3300 3850);
PAINT AQUA (-3300 3850);
FORCEPROP 1 LAST VALUE 2.21K
J 2
(-3050 3850);
DISPLAY 0.617021 (-3050 3850);
PAINT SKYBLUE (-3050 3850);
FORCEPROP 1 LAST PATH I89
J 0
(-3300 3950);
DISPLAY 0.978723 (-3300 3950);
PAINT WHITE (-3300 3950);
DISPLAY INVISIBLE (-3300 3950);
FORCEPROP 2 LAST SEC 1
J 0
(-3300 4000);
DISPLAY 0.680851 (-3300 4000);
PAINT MONO (-3300 4000);
DISPLAY INVISIBLE (-3300 4000);
FORCEPROP 2 LAST SEC_TYPE 0402
J 0
(-3300 4000);
DISPLAY 1.021277 (-3300 4000);
PAINT ORANGE (-3300 4000);
DISPLAY INVISIBLE (-3300 4000);
FORCEPROP 2 LAST CDS_LIB mstr_discrete
J 0
(-3250 3800);
PAINT ORANGE (-3250 3800);
DISPLAY INVISIBLE (-3250 3800);
FORCEADD OFFPAGE..4
(1400 3225);
FORCEPROP 2 LAST $XR0 120 
J 0
(1586 3225);
DISPLAY 0.638298 (1586 3225);
PAINT MONO (1586 3225);
FORCEPROP 2 LAST BOM_COST SB
J 0
(1150 3275);
DISPLAY 1.361702 (1150 3275);
PAINT ORANGE (1150 3275);
DISPLAY INVISIBLE (1150 3275);
FORCEPROP 2 LAST ROOM SB
J 0
(1150 3275);
DISPLAY 1.361702 (1150 3275);
PAINT ORANGE (1150 3275);
DISPLAY INVISIBLE (1150 3275);
FORCEPROP 2 LAST CDS_LIB mstr_standard
J 0
(1400 3225);
PAINT ORANGE (1400 3225);
DISPLAY INVISIBLE (1400 3225);
FORCEPROP 2 LAST PATH I9
J 0
(1600 3275);
DISPLAY 1.021277 (1600 3275);
PAINT ORANGE (1600 3275);
DISPLAY INVISIBLE (1600 3275);
FORCEPROP 1 LAST OFFPAGE TRUE
J 0
(1725 3100);
DISPLAY 0.872340 (1725 3100);
PAINT GREEN (1725 3100);
DISPLAY INVISIBLE (1725 3100);
FORCEPROP 1 LAST COMMENT_BODY TRUE
J 0
(1375 3125);
DISPLAY 0.872340 (1375 3125);
PAINT GREEN (1375 3125);
DISPLAY INVISIBLE (1375 3125);
FORCEADD RES..1
(-3250 3500);
FORCEPROP 1 LAST PACK_TYPE 0402
J 0
(-2925 3550);
DISPLAY 0.617021 (-2925 3550);
PAINT SKYBLUE (-2925 3550);
FORCEPROP 1 LAST WATTAGE 1/16W
J 2
(-2700 3550);
DISPLAY 0.617021 (-2700 3550);
PAINT SKYBLUE (-2700 3550);
FORCEPROP 1 LAST MATERIAL CHIP
J 0
(-2675 3550);
DISPLAY 0.617021 (-2675 3550);
PAINT SKYBLUE (-2675 3550);
FORCEPROP 1 LAST TOLERANCE 1%
J 0
(-3025 3550);
DISPLAY 0.617021 (-3025 3550);
PAINT SKYBLUE (-3025 3550);
FORCEPROP 1 LAST PART_NUMBER G21796-112
J 0
(-2550 3550);
DISPLAY 0.617021 (-2550 3550);
PAINT BLUE (-2550 3550);
FORCEPROP 1 LASTPIN (-3350 3500) $PN 1
J 0
(-3338 3512);
DISPLAY 0.617021 (-3338 3512);
PAINT ORANGE (-3338 3512);
FORCEPROP 1 LAST VALUE 2.21K
J 2
(-3050 3550);
DISPLAY 0.617021 (-3050 3550);
PAINT SKYBLUE (-3050 3550);
FORCEPROP 1 LAST LOCATION R1R21
J 0
(-3300 3550);
DISPLAY 0.617021 (-3300 3550);
PAINT AQUA (-3300 3550);
FORCEPROP 1 LASTPIN (-3150 3500) $PN 2
J 0
(-3188 3512);
DISPLAY 0.617021 (-3188 3512);
PAINT ORANGE (-3188 3512);
FORCEPROP 2 LAST CDS_LIB mstr_discrete
J 0
(-3250 3500);
PAINT ORANGE (-3250 3500);
DISPLAY INVISIBLE (-3250 3500);
FORCEPROP 2 LAST SEC_TYPE 0402
J 0
(-3300 3700);
DISPLAY 1.021277 (-3300 3700);
PAINT ORANGE (-3300 3700);
DISPLAY INVISIBLE (-3300 3700);
FORCEPROP 2 LAST SEC 1
J 0
(-3300 3700);
DISPLAY 0.680851 (-3300 3700);
PAINT MONO (-3300 3700);
DISPLAY INVISIBLE (-3300 3700);
FORCEPROP 1 LAST PATH I90
J 0
(-3300 3650);
DISPLAY 0.978723 (-3300 3650);
PAINT WHITE (-3300 3650);
DISPLAY INVISIBLE (-3300 3650);
FORCEADD RES..1
(-3250 3650);
FORCEPROP 1 LAST PACK_TYPE 0402
J 0
(-2925 3700);
DISPLAY 0.617021 (-2925 3700);
PAINT SKYBLUE (-2925 3700);
FORCEPROP 1 LAST TOLERANCE 1%
J 0
(-3025 3700);
DISPLAY 0.617021 (-3025 3700);
PAINT SKYBLUE (-3025 3700);
FORCEPROP 1 LAST PART_NUMBER G21796-112
J 0
(-2550 3700);
DISPLAY 0.617021 (-2550 3700);
PAINT BLUE (-2550 3700);
FORCEPROP 1 LASTPIN (-3350 3650) $PN 1
J 0
(-3338 3662);
DISPLAY 0.617021 (-3338 3662);
PAINT ORANGE (-3338 3662);
FORCEPROP 1 LAST VALUE 2.21K
J 2
(-3050 3700);
DISPLAY 0.617021 (-3050 3700);
PAINT SKYBLUE (-3050 3700);
FORCEPROP 1 LAST LOCATION R1R20
J 0
(-3300 3700);
DISPLAY 0.617021 (-3300 3700);
PAINT AQUA (-3300 3700);
FORCEPROP 1 LASTPIN (-3150 3650) $PN 2
J 0
(-3188 3662);
DISPLAY 0.617021 (-3188 3662);
PAINT ORANGE (-3188 3662);
FORCEPROP 1 LAST WATTAGE 1/16W
J 2
(-2700 3700);
DISPLAY 0.617021 (-2700 3700);
PAINT SKYBLUE (-2700 3700);
FORCEPROP 1 LAST MATERIAL CHIP
J 0
(-2675 3700);
DISPLAY 0.617021 (-2675 3700);
PAINT SKYBLUE (-2675 3700);
FORCEPROP 2 LAST CDS_LIB mstr_discrete
J 0
(-3250 3650);
PAINT ORANGE (-3250 3650);
DISPLAY INVISIBLE (-3250 3650);
FORCEPROP 2 LAST SEC_TYPE 0402
J 0
(-3300 3850);
DISPLAY 1.021277 (-3300 3850);
PAINT ORANGE (-3300 3850);
DISPLAY INVISIBLE (-3300 3850);
FORCEPROP 2 LAST SEC 1
J 0
(-3300 3850);
DISPLAY 0.680851 (-3300 3850);
PAINT MONO (-3300 3850);
DISPLAY INVISIBLE (-3300 3850);
FORCEPROP 1 LAST PATH I91
J 0
(-3300 3800);
DISPLAY 0.978723 (-3300 3800);
PAINT WHITE (-3300 3800);
DISPLAY INVISIBLE (-3300 3800);
FORCEADD RES..1
(-3250 2900);
FORCEPROP 1 LAST PACK_TYPE 0402
J 0
(-2925 2950);
DISPLAY 0.617021 (-2925 2950);
PAINT SKYBLUE (-2925 2950);
FORCEPROP 1 LAST TOLERANCE 1%
J 0
(-3025 2950);
DISPLAY 0.617021 (-3025 2950);
PAINT SKYBLUE (-3025 2950);
FORCEPROP 1 LASTPIN (-3350 2900) $PN 1
J 0
(-3338 2912);
DISPLAY 0.617021 (-3338 2912);
PAINT ORANGE (-3338 2912);
FORCEPROP 1 LAST MATERIAL CHIP
J 0
(-2675 2950);
DISPLAY 0.617021 (-2675 2950);
PAINT SKYBLUE (-2675 2950);
FORCEPROP 1 LAST WATTAGE 1/16W
J 2
(-2700 2950);
DISPLAY 0.617021 (-2700 2950);
PAINT SKYBLUE (-2700 2950);
FORCEPROP 1 LASTPIN (-3150 2900) $PN 2
J 0
(-3188 2912);
DISPLAY 0.617021 (-3188 2912);
PAINT ORANGE (-3188 2912);
FORCEPROP 1 LAST LOCATION R1R22
J 0
(-3300 2950);
DISPLAY 0.617021 (-3300 2950);
PAINT AQUA (-3300 2950);
FORCEPROP 1 LAST VALUE 2.21K
J 2
(-3050 2950);
DISPLAY 0.617021 (-3050 2950);
PAINT SKYBLUE (-3050 2950);
FORCEPROP 1 LAST PART_NUMBER G21796-112
J 0
(-2550 2950);
DISPLAY 0.617021 (-2550 2950);
PAINT BLUE (-2550 2950);
FORCEPROP 2 LAST CDS_LIB mstr_discrete
J 0
(-3250 2900);
PAINT ORANGE (-3250 2900);
DISPLAY INVISIBLE (-3250 2900);
FORCEPROP 2 LAST SEC_TYPE 0402
J 0
(-3300 3100);
DISPLAY 1.021277 (-3300 3100);
PAINT ORANGE (-3300 3100);
DISPLAY INVISIBLE (-3300 3100);
FORCEPROP 2 LAST SEC 1
J 0
(-3300 3100);
DISPLAY 0.680851 (-3300 3100);
PAINT MONO (-3300 3100);
DISPLAY INVISIBLE (-3300 3100);
FORCEPROP 1 LAST PATH I92
J 0
(-3300 3050);
DISPLAY 0.978723 (-3300 3050);
PAINT WHITE (-3300 3050);
DISPLAY INVISIBLE (-3300 3050);
FORCEADD RES..1
(-3250 3350);
FORCEPROP 1 LAST PART_NUMBER G21796-112
J 0
(-2550 3400);
DISPLAY 0.617021 (-2550 3400);
PAINT BLUE (-2550 3400);
FORCEPROP 1 LASTPIN (-3350 3350) $PN 1
J 0
(-3338 3362);
DISPLAY 0.617021 (-3338 3362);
PAINT ORANGE (-3338 3362);
FORCEPROP 1 LAST PACK_TYPE 0402
J 0
(-2925 3400);
DISPLAY 0.617021 (-2925 3400);
PAINT SKYBLUE (-2925 3400);
FORCEPROP 1 LAST TOLERANCE 1%
J 0
(-3025 3400);
DISPLAY 0.617021 (-3025 3400);
PAINT SKYBLUE (-3025 3400);
FORCEPROP 1 LAST WATTAGE 1/16W
J 2
(-2700 3400);
DISPLAY 0.617021 (-2700 3400);
PAINT SKYBLUE (-2700 3400);
FORCEPROP 1 LAST MATERIAL CHIP
J 0
(-2675 3400);
DISPLAY 0.617021 (-2675 3400);
PAINT SKYBLUE (-2675 3400);
FORCEPROP 1 LASTPIN (-3150 3350) $PN 2
J 0
(-3188 3362);
DISPLAY 0.617021 (-3188 3362);
PAINT ORANGE (-3188 3362);
FORCEPROP 1 LAST LOCATION R1R16
J 0
(-3300 3400);
DISPLAY 0.617021 (-3300 3400);
PAINT AQUA (-3300 3400);
FORCEPROP 1 LAST VALUE 2.21K
J 2
(-3050 3400);
DISPLAY 0.617021 (-3050 3400);
PAINT SKYBLUE (-3050 3400);
FORCEPROP 2 LAST CDS_LIB mstr_discrete
J 0
(-3250 3350);
PAINT ORANGE (-3250 3350);
DISPLAY INVISIBLE (-3250 3350);
FORCEPROP 2 LAST SEC_TYPE 0402
J 0
(-3300 3550);
DISPLAY 1.021277 (-3300 3550);
PAINT ORANGE (-3300 3550);
DISPLAY INVISIBLE (-3300 3550);
FORCEPROP 2 LAST SEC 1
J 0
(-3300 3550);
DISPLAY 0.680851 (-3300 3550);
PAINT MONO (-3300 3550);
DISPLAY INVISIBLE (-3300 3550);
FORCEPROP 1 LAST PATH I93
J 0
(-3300 3500);
DISPLAY 0.978723 (-3300 3500);
PAINT WHITE (-3300 3500);
DISPLAY INVISIBLE (-3300 3500);
FORCEADD RES..1
(-3250 3200);
FORCEPROP 1 LASTPIN (-3350 3200) $PN 1
J 0
(-3338 3212);
DISPLAY 0.617021 (-3338 3212);
PAINT ORANGE (-3338 3212);
FORCEPROP 1 LAST PART_NUMBER G21796-112
J 0
(-2550 3250);
DISPLAY 0.617021 (-2550 3250);
PAINT BLUE (-2550 3250);
FORCEPROP 1 LAST PACK_TYPE 0402
J 0
(-2925 3250);
DISPLAY 0.617021 (-2925 3250);
PAINT SKYBLUE (-2925 3250);
FORCEPROP 1 LAST TOLERANCE 1%
J 0
(-3025 3250);
DISPLAY 0.617021 (-3025 3250);
PAINT SKYBLUE (-3025 3250);
FORCEPROP 1 LAST MATERIAL CHIP
J 0
(-2675 3250);
DISPLAY 0.617021 (-2675 3250);
PAINT SKYBLUE (-2675 3250);
FORCEPROP 1 LAST WATTAGE 1/16W
J 2
(-2700 3250);
DISPLAY 0.617021 (-2700 3250);
PAINT SKYBLUE (-2700 3250);
FORCEPROP 1 LASTPIN (-3150 3200) $PN 2
J 0
(-3188 3212);
DISPLAY 0.617021 (-3188 3212);
PAINT ORANGE (-3188 3212);
FORCEPROP 1 LAST LOCATION R1R17
J 0
(-3300 3250);
DISPLAY 0.617021 (-3300 3250);
PAINT AQUA (-3300 3250);
FORCEPROP 1 LAST VALUE 2.21K
J 2
(-3050 3250);
DISPLAY 0.617021 (-3050 3250);
PAINT SKYBLUE (-3050 3250);
FORCEPROP 1 LAST PATH I94
J 0
(-3300 3350);
DISPLAY 0.978723 (-3300 3350);
PAINT WHITE (-3300 3350);
DISPLAY INVISIBLE (-3300 3350);
FORCEPROP 2 LAST SEC 1
J 0
(-3300 3400);
DISPLAY 0.680851 (-3300 3400);
PAINT MONO (-3300 3400);
DISPLAY INVISIBLE (-3300 3400);
FORCEPROP 2 LAST SEC_TYPE 0402
J 0
(-3300 3400);
DISPLAY 1.021277 (-3300 3400);
PAINT ORANGE (-3300 3400);
DISPLAY INVISIBLE (-3300 3400);
FORCEPROP 2 LAST CDS_LIB mstr_discrete
J 0
(-3250 3200);
PAINT ORANGE (-3250 3200);
DISPLAY INVISIBLE (-3250 3200);
FORCEADD RES..1
(-3250 3050);
FORCEPROP 1 LAST MATERIAL CHIP
J 0
(-2675 3100);
DISPLAY 0.617021 (-2675 3100);
PAINT SKYBLUE (-2675 3100);
FORCEPROP 1 LAST TOLERANCE 1%
J 0
(-3025 3100);
DISPLAY 0.617021 (-3025 3100);
PAINT SKYBLUE (-3025 3100);
FORCEPROP 1 LAST LOCATION R1R23
J 0
(-3300 3100);
DISPLAY 0.617021 (-3300 3100);
PAINT AQUA (-3300 3100);
FORCEPROP 1 LAST VALUE 2.21K
J 2
(-3050 3100);
DISPLAY 0.617021 (-3050 3100);
PAINT SKYBLUE (-3050 3100);
FORCEPROP 1 LASTPIN (-3350 3050) $PN 1
J 0
(-3338 3062);
DISPLAY 0.617021 (-3338 3062);
PAINT ORANGE (-3338 3062);
FORCEPROP 1 LAST PART_NUMBER G21796-112
J 0
(-2550 3100);
DISPLAY 0.617021 (-2550 3100);
PAINT BLUE (-2550 3100);
FORCEPROP 1 LAST PACK_TYPE 0402
J 0
(-2925 3100);
DISPLAY 0.617021 (-2925 3100);
PAINT SKYBLUE (-2925 3100);
FORCEPROP 1 LAST WATTAGE 1/16W
J 2
(-2700 3100);
DISPLAY 0.617021 (-2700 3100);
PAINT SKYBLUE (-2700 3100);
FORCEPROP 1 LASTPIN (-3150 3050) $PN 2
J 0
(-3188 3062);
DISPLAY 0.617021 (-3188 3062);
PAINT ORANGE (-3188 3062);
FORCEPROP 2 LAST CDS_LIB mstr_discrete
J 0
(-3250 3050);
PAINT ORANGE (-3250 3050);
DISPLAY INVISIBLE (-3250 3050);
FORCEPROP 2 LAST SEC_TYPE 0402
J 0
(-3300 3250);
DISPLAY 1.021277 (-3300 3250);
PAINT ORANGE (-3300 3250);
DISPLAY INVISIBLE (-3300 3250);
FORCEPROP 2 LAST SEC 1
J 0
(-3300 3250);
DISPLAY 0.680851 (-3300 3250);
PAINT MONO (-3300 3250);
DISPLAY INVISIBLE (-3300 3250);
FORCEPROP 1 LAST PATH I95
J 0
(-3300 3200);
DISPLAY 0.978723 (-3300 3200);
PAINT WHITE (-3300 3200);
DISPLAY INVISIBLE (-3300 3200);
FORCEADD OFFPAGE..2
(-2450 3950);
FORCEPROP 2 LAST $XR1 188 
J 0
(-2141 3950);
DISPLAY 0.638298 (-2141 3950);
PAINT MONO (-2141 3950);
FORCEPROP 2 LAST $XR0 120 
J 0
(-2261 3950);
DISPLAY 0.638298 (-2261 3950);
PAINT MONO (-2261 3950);
FORCEPROP 2 LAST CDS_LIB mstr_standard
J 0
(-2450 3950);
PAINT ORANGE (-2450 3950);
DISPLAY INVISIBLE (-2450 3950);
FORCEPROP 2 LAST PATH I96
J 0
(-2275 4025);
DISPLAY 1.021277 (-2275 4025);
PAINT ORANGE (-2275 4025);
DISPLAY INVISIBLE (-2275 4025);
FORCEPROP 1 LAST OFFPAGE TRUE
J 0
(-2125 3825);
DISPLAY 0.872340 (-2125 3825);
PAINT GREEN (-2125 3825);
DISPLAY INVISIBLE (-2125 3825);
FORCEPROP 1 LAST COMMENT_BODY TRUE
J 0
(-2495 3855);
DISPLAY 0.872340 (-2495 3855);
PAINT GREEN (-2495 3855);
DISPLAY INVISIBLE (-2495 3855);
FORCEADD OFFPAGE..2
(-2450 3650);
FORCEPROP 2 LAST $XR1 188 
J 0
(-2141 3650);
DISPLAY 0.638298 (-2141 3650);
PAINT MONO (-2141 3650);
FORCEPROP 2 LAST $XR0 120 
J 0
(-2261 3650);
DISPLAY 0.638298 (-2261 3650);
PAINT MONO (-2261 3650);
FORCEPROP 1 LAST COMMENT_BODY TRUE
J 0
(-2495 3555);
DISPLAY 0.872340 (-2495 3555);
PAINT GREEN (-2495 3555);
DISPLAY INVISIBLE (-2495 3555);
FORCEPROP 1 LAST OFFPAGE TRUE
J 0
(-2125 3525);
DISPLAY 0.872340 (-2125 3525);
PAINT GREEN (-2125 3525);
DISPLAY INVISIBLE (-2125 3525);
FORCEPROP 2 LAST PATH I97
J 0
(-2275 3725);
DISPLAY 1.021277 (-2275 3725);
PAINT ORANGE (-2275 3725);
DISPLAY INVISIBLE (-2275 3725);
FORCEPROP 2 LAST CDS_LIB mstr_standard
J 0
(-2450 3650);
PAINT ORANGE (-2450 3650);
DISPLAY INVISIBLE (-2450 3650);
FORCEADD OFFPAGE..2
(-2450 3350);
FORCEPROP 2 LAST $XR1 188 
J 0
(-2141 3350);
DISPLAY 0.638298 (-2141 3350);
PAINT MONO (-2141 3350);
FORCEPROP 2 LAST $XR0 120 
J 0
(-2261 3350);
DISPLAY 0.638298 (-2261 3350);
PAINT MONO (-2261 3350);
FORCEPROP 2 LAST CDS_LIB mstr_standard
J 0
(-2450 3350);
PAINT ORANGE (-2450 3350);
DISPLAY INVISIBLE (-2450 3350);
FORCEPROP 2 LAST PATH I98
J 0
(-2275 3425);
DISPLAY 1.021277 (-2275 3425);
PAINT ORANGE (-2275 3425);
DISPLAY INVISIBLE (-2275 3425);
FORCEPROP 1 LAST OFFPAGE TRUE
J 0
(-2125 3225);
DISPLAY 0.872340 (-2125 3225);
PAINT GREEN (-2125 3225);
DISPLAY INVISIBLE (-2125 3225);
FORCEPROP 1 LAST COMMENT_BODY TRUE
J 0
(-2495 3255);
DISPLAY 0.872340 (-2495 3255);
PAINT GREEN (-2495 3255);
DISPLAY INVISIBLE (-2495 3255);
FORCEADD OFFPAGE..2
(-2450 3050);
FORCEPROP 2 LAST $XR1 188 
J 0
(-2141 3050);
DISPLAY 0.638298 (-2141 3050);
PAINT MONO (-2141 3050);
FORCEPROP 2 LAST $XR0 120 
J 0
(-2261 3050);
DISPLAY 0.638298 (-2261 3050);
PAINT MONO (-2261 3050);
FORCEPROP 2 LAST CDS_LIB mstr_standard
J 0
(-2450 3050);
PAINT ORANGE (-2450 3050);
DISPLAY INVISIBLE (-2450 3050);
FORCEPROP 2 LAST PATH I99
J 0
(-2275 3125);
DISPLAY 1.021277 (-2275 3125);
PAINT ORANGE (-2275 3125);
DISPLAY INVISIBLE (-2275 3125);
FORCEPROP 1 LAST OFFPAGE TRUE
J 0
(-2125 2925);
DISPLAY 0.872340 (-2125 2925);
PAINT GREEN (-2125 2925);
DISPLAY INVISIBLE (-2125 2925);
FORCEPROP 1 LAST COMMENT_BODY TRUE
J 0
(-2495 2955);
DISPLAY 0.872340 (-2495 2955);
PAINT GREEN (-2495 2955);
DISPLAY INVISIBLE (-2495 2955);
FORCEADD INTEL_CORP_BPAGE..1
(4250 200);
FORCEPROP 1 LAST CDS_CON_LAST_MODIFIED Fri Jun 16 17:49:09 2017
J 0
(2825 525);
PAINT ORANGE (2825 525);
DISPLAY INVISIBLE (2825 525);
FORCEPROP 1 LAST CUSTOM_TXT_CDS <CURRENT_DESIGN_SHEET> OF <TOTAL_DESIGN_SHEETS>
J 0
(3750 225);
PAINT ORANGE (3750 225);
FORCEPROP 1 LAST CUSTOM_TXT_CDS <CON_LAST_MODIFIED>
J 0
(250 300);
PAINT ORANGE (250 300);
FORCEPROP 2 LAST CUSTOM_TXT_CDS <XR_PAGE_TITLE>
J 0
(-3640 5450);
DISPLAY 0.638298 (-3640 5450);
PAINT PINK (-3640 5450);
DISPLAY INVISIBLE (-3640 5450);
FORCEPROP 1 LAST SCH_TITLE OCP MODULE CONN C
J 0
(-3700 250);
DISPLAY 1.212766 (-3700 250);
PAINT YELLOW (-3700 250);
FORCEPROP 2 LAST PAGE_BORDER TRUE
J 0
(-3640 5450);
DISPLAY 0.638298 (-3640 5450);
PAINT PINK (-3640 5450);
DISPLAY INVISIBLE (-3640 5450);
FORCEPROP 2 LAST CDS_LIB mstr_symbols
J 0
(4250 200);
PAINT MONO (4250 200);
DISPLAY INVISIBLE (4250 200);
FORCEPROP 1 LAST COMMENT_BODY TRUE
J 0
(4262 212);
DISPLAY 0.468085 (4262 212);
PAINT PEACH (4262 212);
DISPLAY INVISIBLE (4262 212);
FORCEPROP 2 LAST CDS_XR_PAGE_TITLE CR-188 : @BASEBOARD_FAB2_LIB.BASEBOARD_FAB2(SCH_1):PAGE188
J 0
(-3640 5450);
DISPLAY 0.638298 (-3640 5450);
PAINT PINK (-3640 5450);
DISPLAY INVISIBLE (-3640 5450);
FORCEADD CAD_NOTE..1
(-1700 775);
FORCEPROP 0 LAST L1 PLACE NEAR THE IO SLOT.
J 0
(-1850 675);
DISPLAY 0.617021 (-1850 675);
PAINT WHITE (-1850 675);
FORCEPROP 2 LAST BOM_COST SM_CONTROLLER
J 0
(-1850 725);
DISPLAY 0.744681 (-1850 725);
PAINT MONO (-1850 725);
DISPLAY INVISIBLE (-1850 725);
FORCEPROP 2 LAST CDS_LIB mstr_symbols
J 0
(-1700 775);
DISPLAY 0.744681 (-1700 775);
PAINT MONO (-1700 775);
DISPLAY INVISIBLE (-1700 775);
FORCEPROP 2 LAST ROOM BMC
J 0
(-1850 725);
DISPLAY 0.744681 (-1850 725);
PAINT MONO (-1850 725);
DISPLAY INVISIBLE (-1850 725);
FORCEPROP 1 LAST COMMENT_BODY TRUE
J 0
(-1675 875);
DISPLAY 0.978723 (-1675 875);
PAINT GREEN (-1675 875);
DISPLAY INVISIBLE (-1675 875);
FORCEADD CAD_NOTE..1
(2625 2300);
FORCEPROP 0 LAST L1 PLEASE PLACE CAPS WITHIN 1 INCH OF PCH
J 0
(2500 2175);
DISPLAY 1.021277 (2500 2175);
PAINT ORANGE (2500 2175);
FORCEPROP 2 LAST CDS_LIB mstr_symbols
J 0
(2625 2300);
PAINT ORANGE (2625 2300);
DISPLAY INVISIBLE (2625 2300);
FORCEPROP 1 LAST COMMENT_BODY TRUE
J 0
(2650 2400);
DISPLAY 0.978723 (2650 2400);
PAINT ORANGE (2650 2400);
DISPLAY INVISIBLE (2650 2400);
WIRE 16 -1 (-3500 4150)(-3500 3950);
WIRE 16 -1 (-3500 3950)(-3500 3800);
WIRE 16 -1 (-3350 3950)(-3500 3950);
WIRE 16 -1 (-3500 3650)(-3500 3800);
WIRE 16 -1 (-3350 3800)(-3500 3800);
WIRE 16 -1 (-3500 3500)(-3500 3650);
WIRE 16 -1 (-3350 3650)(-3500 3650);
WIRE 16 -1 (-3500 3350)(-3500 3500);
WIRE 16 -1 (-3350 3500)(-3500 3500);
WIRE 16 -1 (-3500 3200)(-3500 3350);
WIRE 16 -1 (-3350 3350)(-3500 3350);
WIRE 16 -1 (-3500 3050)(-3500 3200);
WIRE 16 -1 (-3350 3200)(-3500 3200);
WIRE 16 -1 (-3500 2900)(-3500 3050);
WIRE 16 -1 (-3350 3050)(-3500 3050);
WIRE 16 -1 (-3500 2750)(-3500 2900);
WIRE 16 -1 (-3350 2900)(-3500 2900);
WIRE 16 -1 (-3500 2750)(-3500 2350);
WIRE 16 -1 (-3500 2750)(-3350 2750);
WIRE 16 -1 (-3500 2350)(-3500 2200);
WIRE 16 -1 (-3500 2350)(-3350 2350);
WIRE 16 -1 (-3500 2200)(-3500 2050);
WIRE 16 -1 (-3500 2200)(-3350 2200);
WIRE 16 -1 (-3500 2050)(-3500 1900);
WIRE 16 -1 (-3350 2050)(-3500 2050);
WIRE 16 -1 (-3500 1900)(-3350 1900);
WIRE 16 -1 (-3400 2600)(-3400 2575);
WIRE 16 -1 (-3350 2600)(-3400 2600);
WIRE 16 -1 (650 2275)(650 2050);
WIRE 16 -1 (650 2425)(650 2275);
WIRE 16 -1 (450 2275)(650 2275);
WIRE 16 -1 (650 2575)(650 2425);
WIRE 16 -1 (450 2425)(650 2425);
WIRE 16 -1 (650 2725)(650 2575);
WIRE 16 -1 (450 2575)(650 2575);
WIRE 16 -1 (650 2875)(650 2725);
WIRE 16 -1 (450 2725)(650 2725);
WIRE 16 -1 (650 3025)(650 2875);
WIRE 16 -1 (450 2875)(650 2875);
WIRE 16 -1 (650 3175)(650 3025);
WIRE 16 -1 (450 3025)(650 3025);
WIRE 16 -1 (650 3325)(650 3175);
WIRE 16 -1 (450 3175)(650 3175);
WIRE 16 -1 (650 3475)(650 3325);
WIRE 16 -1 (450 3325)(650 3325);
WIRE 16 -1 (450 3475)(650 3475);
WIRE 16 -1 (-475 2425)(-475 2050);
WIRE 16 -1 (-475 2575)(-475 2425);
WIRE 16 -1 (-150 2425)(-475 2425);
WIRE 16 -1 (-475 2725)(-475 2575);
WIRE 16 -1 (-150 2575)(-475 2575);
WIRE 16 -1 (-475 2875)(-475 2725);
WIRE 16 -1 (-150 2725)(-475 2725);
WIRE 16 -1 (-475 3025)(-475 2875);
WIRE 16 -1 (-150 2875)(-475 2875);
WIRE 16 -1 (-475 3175)(-475 3025);
WIRE 16 -1 (-150 3025)(-475 3025);
WIRE 16 -1 (-475 3325)(-475 3175);
WIRE 16 -1 (-150 3175)(-475 3175);
WIRE 16 -1 (-475 3475)(-475 3325);
WIRE 16 -1 (-150 3325)(-475 3325);
WIRE 16 -1 (-475 3625)(-475 3475);
WIRE 16 -1 (-150 3475)(-475 3475);
WIRE 16 -1 (-150 3625)(-475 3625);
WIRE 16 -1 (200 825)(200 975);
WIRE 16 -1 (200 975)(475 975);
WIRE 16 -1 (-75 975)(200 975);
WIRE 16 -1 (-75 975)(-525 975);
WIRE 16 -1 (-75 1200)(-75 975);
WIRE 16 -1 (475 975)(1000 975);
WIRE 16 -1 (475 1200)(475 975);
WIRE 16 -1 (1000 975)(2050 975);
WIRE 16 -1 (1000 1200)(1000 975);
WIRE 16 -1 (-525 975)(-950 975);
WIRE 16 -1 (-525 975)(-525 1200);
WIRE 16 -1 (-1400 975)(-950 975);
WIRE 16 -1 (-950 1200)(-950 975);
WIRE 16 -1 (2400 975)(2050 975);
WIRE 16 -1 (2050 975)(2050 1200);
WIRE 16 -1 (2925 975)(2400 975);
WIRE 16 -1 (2400 1200)(2400 975);
WIRE 16 -1 (-1825 975)(-1400 975);
WIRE 16 -1 (-1400 1200)(-1400 975);
WIRE 16 -1 (-1825 1200)(-1825 975);
WIRE 16 -1 (3300 975)(2925 975);
WIRE 16 -1 (2925 975)(2925 1200);
WIRE 16 -1 (3300 1200)(3300 975);
WIRE 16 -1 (875 3875)(875 3775);
WIRE 16 -1 (875 3775)(875 3725);
WIRE 16 -1 (875 3775)(450 3775);
WIRE 16 -1 (875 3725)(875 3675);
WIRE 16 -1 (875 3725)(450 3725);
WIRE 16 -1 (875 3675)(450 3675);
WIRE 16 -1 (2050 1525)(2050 1575);
WIRE 16 -1 (2400 1525)(2050 1525);
WIRE 16 -1 (2050 1400)(2050 1525);
WIRE 16 -1 (2400 1400)(2400 1525);
WIRE 16 -1 (850 1525)(850 1575);
WIRE 16 -1 (850 1525)(1000 1525);
WIRE 16 -1 (850 1525)(475 1525);
WIRE 16 -1 (475 1400)(475 1525);
WIRE 16 -1 (1000 1400)(1000 1525);
WIRE 16 -1 (-1100 1525)(-1100 1575);
WIRE 16 -1 (-1100 1525)(-950 1525);
WIRE 16 -1 (-1400 1525)(-1100 1525);
WIRE 16 -1 (-1400 1525)(-1825 1525);
WIRE 16 -1 (-1400 1400)(-1400 1525);
WIRE 16 -1 (-525 1525)(-950 1525);
WIRE 16 -1 (-950 1400)(-950 1525);
WIRE 16 -1 (-75 1525)(-525 1525);
WIRE 16 -1 (-525 1400)(-525 1525);
WIRE 16 -1 (-1825 1400)(-1825 1525);
WIRE 16 -1 (-75 1525)(-75 1400);
WIRE 16 -1 (3300 1600)(3300 1500);
WIRE 16 -1 (3300 1500)(2925 1500);
WIRE 16 -1 (3300 1400)(3300 1500);
WIRE 16 -1 (2925 1400)(2925 1500);
WIRE 3 2175 (750 2600)(750 2450);
WIRE 3 2175 (750 3200)(750 3050);
WIRE 3 2175 (750 2600)(1700 2600);
WIRE 3 2175 (750 2450)(1700 2450);
WIRE 3 2175 (1700 2500)(1700 2450);
WIRE 3 2175 (1700 2600)(1700 2500);
WIRE 3 2175 (750 3200)(1700 3200);
WIRE 3 2175 (750 3050)(1700 3050);
WIRE 3 2175 (1700 3100)(1700 3050);
WIRE 3 2175 (1700 3200)(1700 3100);
WIRE 3 2175 (1700 2500)(1800 2500);
WIRE 3 2175 (1800 3100)(1800 2500);
WIRE 3 2175 (1700 3100)(1800 3100);
WIRE 3 2175 (1800 3150)(1800 3100);
WIRE 16 -1 (-1600 4975)(-1600 4500);
WIRE 16 -1 (-925 4975)(-1600 4975);
WIRE 16 -1 (-925 4975)(-925 4500);
WIRE 16 -1 (-925 4500)(-1600 4500);
WIRE 16 -1 (-225 4500)(-925 4500);
WIRE 16 -1 (-225 4975)(-925 4975);
WIRE 16 -1 (-225 4975)(-225 4500);
WIRE 16 -1 (-1600 4500)(-2475 4500);
WIRE 16 -1 (-1600 4975)(-2475 4975);
WIRE 16 -1 (-2475 4975)(-2475 4500);
WIRE 16 -1 (-3325 4975)(-2475 4975);
WIRE 16 -1 (-3325 4500)(-2475 4500);
WIRE 16 -1 (-3325 4975)(-3325 4500);
WIRE 16 -1 (425 4975)(-225 4975);
WIRE 16 -1 (425 4500)(-225 4500);
WIRE 16 -1 (425 4975)(425 4500);
WIRE 16 -1 (1150 4500)(425 4500);
WIRE 16 -1 (1150 4975)(425 4975);
WIRE 16 -1 (-3625 4500)(-3325 4500);
WIRE 16 -1 (-3625 4975)(-3325 4975);
WIRE 16 -1 (-3625 4975)(-3625 4800);
WIRE 16 -1 (-3625 4600)(-3625 4500);
WIRE 16 -1 (1150 4975)(1150 4800);
WIRE 16 -1 (-3625 4800)(1150 4800);
WIRE 16 -1 (1150 4600)(1150 4500);
WIRE 16 -1 (-3625 4600)(1150 4600);
WIRE 16 -1 (1150 4600)(1150 4700);
WIRE 16 -1 (1150 4700)(1150 4800);
WIRE 16 -1 (-3625 4700)(-3625 4600);
WIRE 16 -1 (-3625 4700)(-3625 4800);
WIRE 16 -1 (-3625 4700)(1150 4700);
WIRE 16 -1 (-150 2225)(-1350 2225);
FORCEPROP 0 LAST SIG_NAME FM_GBE3_LVC3_MOD_ABS
J 0
(-1300 2235);
DISPLAY 0.617021 (-1300 2235);
PAINT ORANGE (-1300 2235);
WIRE 16 -1 (1350 2675)(450 2675);
FORCEPROP 0 LAST SIG_NAME LED_GBE_P3_0
J 0
(775 2685);
DISPLAY 0.617021 (775 2685);
PAINT ORANGE (775 2685);
WIRE 16 -1 (1350 2625)(450 2625);
FORCEPROP 0 LAST SIG_NAME LED_GBE_P3_1
J 0
(775 2635);
DISPLAY 0.617021 (775 2635);
PAINT ORANGE (775 2635);
WIRE 16 -1 (1350 2325)(450 2325);
FORCEPROP 0 LAST SIG_NAME SMB_PCH_MEZZ_LOM2_SDA
J 0
(775 2335);
DISPLAY 0.617021 (775 2335);
PAINT ORANGE (775 2335);
WIRE 3 2175 (750 2275)(1900 2275);
WIRE 3 2175 (1900 2275)(1900 2175);
WIRE 3 2175 (750 2275)(750 2175);
WIRE 3 2175 (750 2175)(1900 2175);
WIRE 3 682 (4150 3900)(2050 3900);
WIRE 3 682 (4150 3200)(4150 3900);
WIRE 3 682 (2050 3900)(2050 3200);
WIRE 3 682 (2050 3200)(4150 3200);
WIRE 16 -1 (2975 2925)(2425 2925);
FORCEPROP 2 LAST SIG_NAME KR_P0_OCP_RX_DP
J 0
(2490 2935);
DISPLAY 0.617021 (2490 2935);
PAINT ORANGE (2490 2935);
WIRE 3 682 (-3550 1850)(-2200 1850);
WIRE 3 682 (-3550 2450)(-3550 1850);
WIRE 3 682 (-2200 1850)(-2200 2450);
WIRE 3 682 (-2200 2450)(-3550 2450);
WIRE 16 -1 (-2500 2050)(-3150 2050);
FORCEPROP 0 LAST SIG_NAME FM_GBE2_LVC3_MOD_ABS
J 0
(-3100 2060);
DISPLAY 0.617021 (-3100 2060);
PAINT ORANGE (-3100 2060);
FORCEPROP 2 LASTPROP $XR1 120 
J 0
(-2350 2050);
DISPLAY 0.638298 (-2350 2050);
PAINT MONO (-2350 2050);
FORCEPROP 2 LASTPROP $XR0 188 
J 0
(-2470 2050);
DISPLAY 0.638298 (-2470 2050);
PAINT MONO (-2470 2050);
WIRE 16 -1 (-2500 2200)(-3150 2200);
FORCEPROP 0 LAST SIG_NAME FM_GBE1_LVC3_MOD_ABS
J 0
(-3100 2210);
DISPLAY 0.617021 (-3100 2210);
PAINT ORANGE (-3100 2210);
FORCEPROP 2 LASTPROP $XR1 120 
J 0
(-2350 2200);
DISPLAY 0.638298 (-2350 2200);
PAINT MONO (-2350 2200);
FORCEPROP 2 LASTPROP $XR0 188 
J 0
(-2470 2200);
DISPLAY 0.638298 (-2470 2200);
PAINT MONO (-2470 2200);
WIRE 16 -1 (-2500 2350)(-3150 2350);
FORCEPROP 0 LAST SIG_NAME FM_GBE0_LVC3_MOD_ABS
J 0
(-3100 2360);
DISPLAY 0.617021 (-3100 2360);
PAINT ORANGE (-3100 2360);
FORCEPROP 2 LASTPROP $XR1 120 
J 0
(-2350 2350);
DISPLAY 0.638298 (-2350 2350);
PAINT MONO (-2350 2350);
FORCEPROP 2 LASTPROP $XR0 188 
J 0
(-2470 2350);
DISPLAY 0.638298 (-2470 2350);
PAINT MONO (-2470 2350);
WIRE 3 682 (-3550 2850)(-3550 2500);
WIRE 3 682 (-2200 2850)(-3550 2850);
WIRE 3 682 (-3550 2500)(-2200 2500);
WIRE 3 682 (-2200 2500)(-2200 2850);
WIRE 3 2175 (-725 2750)(-725 2600);
WIRE 3 2175 (-725 3050)(-725 2900);
WIRE 3 2175 (-1375 2750)(-725 2750);
WIRE 3 2175 (-1375 2600)(-725 2600);
WIRE 3 2175 (-725 3650)(-725 3500);
WIRE 3 2175 (-1375 3650)(-725 3650);
WIRE 3 2175 (-1375 2650)(-1375 2600);
WIRE 3 2175 (-1375 2750)(-1375 2650);
WIRE 3 2175 (-1375 3050)(-725 3050);
WIRE 3 2175 (-1375 2900)(-725 2900);
WIRE 3 2175 (-1375 2950)(-1375 2900);
WIRE 3 2175 (-1375 3050)(-1375 2950);
WIRE 3 2175 (-2000 2650)(-1375 2650);
WIRE 3 2175 (-1375 3650)(-1375 3500);
WIRE 3 2175 (-1375 3500)(-725 3500);
WIRE 3 2175 (-2000 3550)(-2000 3500);
WIRE 3 2175 (-2000 3500)(-1375 3500);
WIRE 3 2175 (-2000 2950)(-2000 2650);
WIRE 3 2175 (-2000 2950)(-1375 2950);
WIRE 3 2175 (-2000 3250)(-2000 2950);
WIRE 3 2175 (-2000 3500)(-2000 3250);
WIRE 3 2175 (-2000 3250)(-1375 3250);
WIRE 3 2175 (-1375 3350)(-1375 3250);
WIRE 3 2175 (-1375 3250)(-1375 3200);
WIRE 3 2175 (-1375 3200)(-725 3200);
WIRE 3 2175 (-1375 3350)(-725 3350);
WIRE 3 2175 (-725 3350)(-725 3200);
WIRE 16 -1 (-3000 2600)(-3150 2600);
WIRE 16 -1 (-3150 2750)(-3000 2750);
WIRE 16 -1 (-3000 2750)(-3000 2600);
WIRE 16 -1 (-2500 2750)(-3000 2750);
FORCEPROP 0 LAST SIG_NAME EXT_MDIO_I2C_SEL
J 0
(-2950 2760);
DISPLAY 0.617021 (-2950 2760);
PAINT ORANGE (-2950 2760);
FORCEPROP 2 LASTPROP $XR0 188 
J 0
(-2470 2750);
DISPLAY 0.638298 (-2470 2750);
PAINT MONO (-2470 2750);
WIRE 16 -1 (-2500 1900)(-3150 1900);
FORCEPROP 0 LAST SIG_NAME FM_GBE3_LVC3_MOD_ABS
J 0
(-3100 1910);
DISPLAY 0.617021 (-3100 1910);
PAINT ORANGE (-3100 1910);
FORCEPROP 2 LASTPROP $XR1 120 
J 0
(-2350 1900);
DISPLAY 0.638298 (-2350 1900);
PAINT MONO (-2350 1900);
FORCEPROP 2 LASTPROP $XR0 188 
J 0
(-2470 1900);
DISPLAY 0.638298 (-2470 1900);
PAINT MONO (-2470 1900);
WIRE 16 -1 (-150 2775)(-1350 2775);
FORCEPROP 0 LAST SIG_NAME SMB_PCH_MEZZ_LOM0_SDA
J 0
(-1300 2785);
DISPLAY 0.617021 (-1300 2785);
PAINT ORANGE (-1300 2785);
WIRE 16 -1 (-150 2475)(-1350 2475);
FORCEPROP 0 LAST SIG_NAME SMB_PCH_MEZZ_LOM1_SDA
J 0
(-1300 2485);
DISPLAY 0.617021 (-1300 2485);
PAINT ORANGE (-1300 2485);
WIRE 16 -1 (1350 2825)(450 2825);
FORCEPROP 2 LAST SIG_NAME KR_P0_OCP_RX_DP
J 0
(775 2835);
DISPLAY 0.617021 (775 2835);
PAINT ORANGE (775 2835);
WIRE 16 -1 (1350 2775)(450 2775);
FORCEPROP 2 LAST SIG_NAME KR_P0_OCP_RX_DN
J 0
(775 2785);
DISPLAY 0.617021 (775 2785);
PAINT ORANGE (775 2785);
WIRE 16 -1 (1350 2525)(450 2525);
FORCEPROP 2 LAST SIG_NAME KR_P1_OCP_RX_DP
J 0
(775 2535);
DISPLAY 0.617021 (775 2535);
PAINT ORANGE (775 2535);
WIRE 16 -1 (1350 2475)(450 2475);
FORCEPROP 2 LAST SIG_NAME KR_P1_OCP_RX_DN
J 0
(775 2485);
DISPLAY 0.617021 (775 2485);
PAINT ORANGE (775 2485);
WIRE 16 -1 (-150 2325)(-1350 2325);
FORCEPROP 0 LAST SIG_NAME SMB_PCH_MEZZ_LOM3_SDA
J 0
(-1300 2335);
DISPLAY 0.617021 (-1300 2335);
PAINT ORANGE (-1300 2335);
WIRE 16 -1 (-150 2275)(-1350 2275);
FORCEPROP 0 LAST SIG_NAME FM_GBE2_LVC3_MOD_ABS
J 0
(-1300 2285);
DISPLAY 0.617021 (-1300 2285);
PAINT ORANGE (-1300 2285);
WIRE 16 -1 (1375 2225)(450 2225);
FORCEPROP 0 LAST SIG_NAME FM_OCP_MEZZC_PRES_N
J 0
(775 2235);
DISPLAY 0.617021 (775 2235);
PAINT ORANGE (775 2235);
WIRE 16 -1 (1375 2925)(450 2925);
FORCEPROP 0 LAST SIG_NAME TP_SHARED_KR_MDIO_0
J 0
(775 2935);
DISPLAY 0.617021 (775 2935);
PAINT ORANGE (775 2935);
FORCEPROP 2 LASTPROP $XRERR UNIQUE?
J 0
(1405 2925);
DISPLAY 0.638298 (1405 2925);
PAINT MONO (1405 2925);
DISPLAY INVISIBLE (1405 2925);
WIRE 16 -1 (1375 2975)(450 2975);
FORCEPROP 0 LAST SIG_NAME TP_SHARED_KR_MDC_0
J 0
(775 2985);
DISPLAY 0.617021 (775 2985);
PAINT ORANGE (775 2985);
FORCEPROP 2 LASTPROP $XRERR UNIQUE?
J 0
(1405 2975);
DISPLAY 0.638298 (1405 2975);
PAINT MONO (1405 2975);
DISPLAY INVISIBLE (1405 2975);
WIRE 16 -1 (-150 3075)(-1350 3075);
FORCEPROP 0 LAST SIG_NAME LED_GBE_P2_1
J 0
(-1300 3085);
DISPLAY 0.617021 (-1300 3085);
PAINT ORANGE (-1300 3085);
WIRE 16 -1 (-150 3125)(-1350 3125);
FORCEPROP 0 LAST SIG_NAME LED_GBE_P2_0
J 0
(-1300 3135);
DISPLAY 0.617021 (-1300 3135);
PAINT ORANGE (-1300 3135);
WIRE 16 -1 (-3150 3350)(-2500 3350);
FORCEPROP 2 LAST SIG_NAME SMB_PCH_MEZZ_LOM2_SCL
J 0
(-3050 3360);
DISPLAY 0.617021 (-3050 3360);
PAINT ORANGE (-3050 3360);
WIRE 16 -1 (-150 3725)(-1350 3725);
FORCEPROP 0 LAST SIG_NAME SMB_OCP_FRU_STBY_LVC3_SDA
J 0
(-1300 3735);
DISPLAY 0.617021 (-1300 3735);
PAINT ORANGE (-1300 3735);
WIRE 16 -1 (-150 3775)(-1350 3775);
FORCEPROP 0 LAST SIG_NAME SMB_OCP_FRU_STBY_LVC3_SCL
J 0
(-1300 3785);
DISPLAY 0.617021 (-1300 3785);
PAINT ORANGE (-1300 3785);
WIRE 16 -1 (1350 2375)(450 2375);
FORCEPROP 0 LAST SIG_NAME SMB_PCH_MEZZ_LOM2_SCL
J 0
(775 2385);
DISPLAY 0.617021 (775 2385);
PAINT ORANGE (775 2385);
WIRE 16 -1 (-150 2825)(-1350 2825);
FORCEPROP 0 LAST SIG_NAME SMB_PCH_MEZZ_LOM0_SCL
J 0
(-1300 2835);
DISPLAY 0.617021 (-1300 2835);
PAINT ORANGE (-1300 2835);
WIRE 16 -1 (-150 2525)(-1350 2525);
FORCEPROP 0 LAST SIG_NAME SMB_PCH_MEZZ_LOM1_SCL
J 0
(-1300 2535);
DISPLAY 0.617021 (-1300 2535);
PAINT ORANGE (-1300 2535);
WIRE 16 -1 (-150 2375)(-1350 2375);
FORCEPROP 0 LAST SIG_NAME SMB_PCH_MEZZ_LOM3_SCL
J 0
(-1300 2385);
DISPLAY 0.617021 (-1300 2385);
PAINT ORANGE (-1300 2385);
WIRE 16 -1 (1350 3575)(450 3575);
FORCEPROP 0 LAST SIG_NAME FM_GBE0_LVC3_MOD_ABS
J 0
(775 3585);
DISPLAY 0.617021 (775 3585);
PAINT ORANGE (775 3585);
WIRE 16 -1 (1350 3525)(450 3525);
FORCEPROP 0 LAST SIG_NAME FM_GBE1_LVC3_MOD_ABS
J 0
(775 3535);
DISPLAY 0.617021 (775 3535);
PAINT ORANGE (775 3535);
WIRE 16 -1 (1350 3425)(450 3425);
FORCEPROP 2 LAST SIG_NAME KR_P0_OCP_TX_DP
J 0
(775 3435);
DISPLAY 0.617021 (775 3435);
PAINT ORANGE (775 3435);
WIRE 16 -1 (1350 3375)(450 3375);
FORCEPROP 2 LAST SIG_NAME KR_P0_OCP_TX_DN
J 0
(775 3385);
DISPLAY 0.617021 (775 3385);
PAINT ORANGE (775 3385);
WIRE 16 -1 (1350 3275)(450 3275);
FORCEPROP 0 LAST SIG_NAME LED_GBE_P0_0
J 0
(775 3285);
DISPLAY 0.617021 (775 3285);
PAINT ORANGE (775 3285);
WIRE 16 -1 (1350 3225)(450 3225);
FORCEPROP 0 LAST SIG_NAME LED_GBE_P0_1
J 0
(775 3235);
DISPLAY 0.617021 (775 3235);
PAINT ORANGE (775 3235);
WIRE 16 -1 (1350 3125)(450 3125);
FORCEPROP 2 LAST SIG_NAME KR_P1_OCP_TX_DP
J 0
(775 3135);
DISPLAY 0.617021 (775 3135);
PAINT ORANGE (775 3135);
WIRE 16 -1 (1350 3075)(450 3075);
FORCEPROP 2 LAST SIG_NAME KR_P1_OCP_TX_DN
J 0
(775 3085);
DISPLAY 0.617021 (775 3085);
PAINT ORANGE (775 3085);
WIRE 16 -1 (-150 3425)(-1350 3425);
FORCEPROP 0 LAST SIG_NAME LED_GBE_P1_0
J 0
(-1300 3435);
DISPLAY 0.617021 (-1300 3435);
PAINT ORANGE (-1300 3435);
WIRE 16 -1 (-150 3375)(-1350 3375);
FORCEPROP 0 LAST SIG_NAME LED_GBE_P1_1
J 0
(-1300 3385);
DISPLAY 0.617021 (-1300 3385);
PAINT ORANGE (-1300 3385);
WIRE 16 -1 (-150 3675)(-1325 3675);
FORCEPROP 0 LAST SIG_NAME EXT_MDIO_I2C_SEL
J 0
(-1300 3685);
DISPLAY 0.617021 (-1300 3685);
PAINT ORANGE (-1300 3685);
FORCEPROP 2 LASTPROP $XR0 188 
J 0
(-1691 3675);
DISPLAY 0.638298 (-1691 3675);
PAINT MONO (-1691 3675);
WIRE 16 -1 (1375 3625)(450 3625);
FORCEPROP 0 LAST SIG_NAME TP_RSVD<0>
J 0
(775 3635);
DISPLAY 0.617021 (775 3635);
PAINT ORANGE (775 3635);
FORCEPROP 2 LASTPROP $XRERR UNIQUE?
J 0
(1405 3625);
DISPLAY 0.638298 (1405 3625);
PAINT MONO (1405 3625);
DISPLAY INVISIBLE (1405 3625);
WIRE 3 2175 (2750 3125)(3550 3125);
WIRE 3 2175 (3550 4700)(3550 3125);
WIRE 3 2175 (2750 4700)(2750 3125);
WIRE 3 2175 (2750 4700)(3550 4700);
WIRE 16 -1 (-3150 2900)(-2500 2900);
FORCEPROP 2 LAST SIG_NAME SMB_PCH_MEZZ_LOM3_SDA
J 0
(-3050 2910);
DISPLAY 0.617021 (-3050 2910);
PAINT ORANGE (-3050 2910);
WIRE 16 -1 (-3150 3050)(-2500 3050);
FORCEPROP 2 LAST SIG_NAME SMB_PCH_MEZZ_LOM3_SCL
J 0
(-3050 3060);
DISPLAY 0.617021 (-3050 3060);
PAINT ORANGE (-3050 3060);
WIRE 16 -1 (-3150 3200)(-2500 3200);
FORCEPROP 2 LAST SIG_NAME SMB_PCH_MEZZ_LOM2_SDA
J 0
(-3050 3210);
DISPLAY 0.617021 (-3050 3210);
PAINT ORANGE (-3050 3210);
WIRE 16 -1 (-3150 3950)(-2500 3950);
FORCEPROP 2 LAST SIG_NAME SMB_PCH_MEZZ_LOM0_SCL
J 0
(-3050 3960);
DISPLAY 0.617021 (-3050 3960);
PAINT ORANGE (-3050 3960);
WIRE 16 -1 (-3150 3800)(-2500 3800);
FORCEPROP 2 LAST SIG_NAME SMB_PCH_MEZZ_LOM0_SDA
J 0
(-3050 3810);
DISPLAY 0.617021 (-3050 3810);
PAINT ORANGE (-3050 3810);
WIRE 16 -1 (-3150 3650)(-2500 3650);
FORCEPROP 2 LAST SIG_NAME SMB_PCH_MEZZ_LOM1_SCL
J 0
(-3050 3660);
DISPLAY 0.617021 (-3050 3660);
PAINT ORANGE (-3050 3660);
WIRE 16 -1 (-3150 3500)(-2500 3500);
FORCEPROP 2 LAST SIG_NAME SMB_PCH_MEZZ_LOM1_SDA
J 0
(-3050 3510);
DISPLAY 0.617021 (-3050 3510);
PAINT ORANGE (-3050 3510);
WIRE 16 -1 (3175 3700)(3725 3700);
FORCEPROP 2 LAST SIG_NAME KR_P1_OCP_RX_C_DP
J 0
(3290 3710);
DISPLAY 0.617021 (3290 3710);
PAINT ORANGE (3290 3710);
WIRE 16 -1 (2975 3375)(2425 3375);
FORCEPROP 2 LAST SIG_NAME KR_P1_OCP_RX_DN
J 0
(2490 3385);
DISPLAY 0.617021 (2490 3385);
PAINT ORANGE (2490 3385);
WIRE 16 -1 (3175 2600)(3725 2600);
FORCEPROP 2 LAST SIG_NAME KR_P0_OCP_RX_C_DN
J 0
(3290 2610);
DISPLAY 0.617021 (3290 2610);
PAINT ORANGE (3290 2610);
WIRE 16 -1 (2975 2600)(2425 2600);
FORCEPROP 2 LAST SIG_NAME KR_P0_OCP_RX_DN
J 0
(2490 2610);
DISPLAY 0.617021 (2490 2610);
PAINT ORANGE (2490 2610);
WIRE 16 -1 (2975 3700)(2425 3700);
FORCEPROP 2 LAST SIG_NAME KR_P1_OCP_RX_DP
J 0
(2490 3710);
DISPLAY 0.617021 (2490 3710);
PAINT ORANGE (2490 3710);
WIRE 16 -1 (3175 3375)(3725 3375);
FORCEPROP 2 LAST SIG_NAME KR_P1_OCP_RX_C_DN
J 0
(3290 3385);
DISPLAY 0.617021 (3290 3385);
PAINT ORANGE (3290 3385);
WIRE 16 -1 (3175 2925)(3725 2925);
FORCEPROP 2 LAST SIG_NAME KR_P0_OCP_RX_C_DP
J 0
(3290 2935);
DISPLAY 0.617021 (3290 2935);
PAINT ORANGE (3290 2935);
DOT 1 (-225 4500);
DOT 1 (-475 3025);
DOT 1 (-1375 3500);
DOT 1 (-475 3325);
DOT 1 (-475 2725);
DOT 1 (-950 1525);
DOT 1 (850 1525);
DOT 1 (-2000 2950);
DOT 1 (-2000 3250);
DOT 1 (-1375 2650);
DOT 1 (-1375 2950);
DOT 1 (650 3025);
DOT 1 (425 4500);
DOT 1 (-1600 4500);
DOT 1 (1150 4600);
DOT 1 (-1400 975);
DOT 1 (-525 975);
DOT 1 (-950 975);
DOT 1 (-1100 1525);
DOT 1 (-75 975);
DOT 1 (200 975);
DOT 1 (1000 975);
DOT 1 (2050 975);
DOT 1 (2400 975);
DOT 1 (2050 1525);
DOT 1 (2925 975);
DOT 1 (3300 1500);
DOT 1 (650 2725);
DOT 1 (650 3175);
DOT 1 (-475 2425);
DOT 1 (1150 4700);
DOT 1 (1150 4800);
DOT 1 (425 4975);
DOT 1 (-225 4975);
DOT 1 (-925 4500);
DOT 1 (-925 4975);
DOT 1 (-1600 4975);
DOT 1 (-2475 4500);
DOT 1 (-2475 4975);
DOT 1 (-3325 4500);
DOT 1 (-3325 4975);
DOT 1 (-3625 4800);
DOT 1 (-3625 4700);
DOT 1 (-3625 4600);
DOT 1 (-1375 3250);
DOT 1 (650 2575);
DOT 1 (1800 3100);
DOT 1 (1700 2500);
DOT 1 (1700 3100);
DOT 1 (650 2425);
DOT 1 (-525 1525);
DOT 1 (650 2875);
DOT 1 (-1400 1525);
DOT 1 (-2000 3500);
DOT 1 (-3500 3950);
DOT 1 (-3500 3650);
DOT 1 (-3500 3800);
DOT 1 (-3500 3500);
DOT 1 (-3500 3350);
DOT 1 (-3500 3050);
DOT 1 (-3500 2750);
DOT 1 (-3500 3200);
DOT 1 (-3500 2900);
DOT 1 (-3500 2350);
DOT 1 (-3500 2200);
DOT 1 (-3500 2050);
DOT 1 (-3000 2750);
DOT 1 (875 3725);
DOT 1 (650 3325);
DOT 1 (875 3775);
DOT 1 (-475 3475);
DOT 1 (-475 3175);
DOT 1 (-475 2875);
DOT 1 (-475 2575);
DOT 1 (650 2275);
DOT 1 (475 975);
FORCENOTE
FCI PLUG # ON OCP MEZZ
(-3275 4900) 0;
DISPLAY LEFT (-3275 4900);
DISPLAY 1.021277 (-3275 4900);
PAINT PURPLE (-3275 4900);
FORCENOTE
TP FAB1 DELETE CAPS 0106
(2625 4725) 0;
DISPLAY LEFT (2625 4725);
DISPLAY 1.021277 (2625 4725);
PAINT RED (2625 4725);
FORCENOTE
61082-081402LF
(-3275 4625) 0;
DISPLAY LEFT (-3275 4625);
DISPLAY 1.021277 (-3275 4625);
PAINT PURPLE (-3275 4625);
FORCENOTE
10135584-641402LF
(-3275 4525) 0;
DISPLAY LEFT (-3275 4525);
DISPLAY 1.021277 (-3275 4525);
PAINT PURPLE (-3275 4525);
FORCENOTE
61082-121402LF
(-1550 4725) 0;
DISPLAY LEFT (-1550 4725);
DISPLAY 1.021277 (-1550 4725);
PAINT PURPLE (-1550 4725);
FORCENOTE
B (80P)
(-3600 4625) 0;
DISPLAY LEFT (-3600 4625);
DISPLAY 1.021277 (-3600 4625);
PAINT PURPLE (-3600 4625);
FORCENOTE
H87568-002
(450 4525) 0;
DISPLAY LEFT (450 4525);
DISPLAY 1.021277 (450 4525);
PAINT PURPLE (450 4525);
FORCENOTE
E67482-008
(450 4625) 0;
DISPLAY LEFT (450 4625);
DISPLAY 1.021277 (450 4625);
PAINT PURPLE (450 4625);
FORCENOTE
(5/8MM STACK)
(-900 4825) 0;
DISPLAY LEFT (-900 4825);
DISPLAY 1.021277 (-900 4825);
PAINT PURPLE (-900 4825);
FORCENOTE
A (120P)
(-3600 4725) 0;
DISPLAY LEFT (-3600 4725);
DISPLAY 1.021277 (-3600 4725);
PAINT PURPLE (-3600 4725);
FORCENOTE
(5MM STACK)
(-3275 4825) 0;
DISPLAY LEFT (-3275 4825);
DISPLAY 1.021277 (-3275 4825);
PAINT PURPLE (-3275 4825);
FORCENOTE
10135583-642402LF
(-200 4525) 0;
DISPLAY LEFT (-200 4525);
DISPLAY 1.021277 (-200 4525);
PAINT PURPLE (-200 4525);
FORCENOTE
61082-082402LF
(-200 4625) 0;
DISPLAY LEFT (-200 4625);
DISPLAY 1.021277 (-200 4625);
PAINT PURPLE (-200 4625);
FORCENOTE
61082-122402LF
(-200 4725) 0;
DISPLAY LEFT (-200 4725);
DISPLAY 1.021277 (-200 4725);
PAINT PURPLE (-200 4725);
FORCENOTE
(12MM STACK)
(-200 4825) 0;
DISPLAY LEFT (-200 4825);
DISPLAY 1.021277 (-200 4825);
PAINT PURPLE (-200 4825);
FORCENOTE
FCI RECPT IPN ON CC
(-900 4900) 0;
DISPLAY LEFT (-900 4900);
DISPLAY 1.021277 (-900 4900);
PAINT PURPLE (-900 4900);
FORCENOTE
MATED HT CONNECTOR P/NS
(-3600 5000) 0;
DISPLAY LEFT (-3600 5000);
DISPLAY 1.021277 (-3600 5000);
PAINT PURPLE (-3600 5000);
FORCENOTE
FCI RECPT IPN ON CC
(450 4900) 0;
DISPLAY LEFT (450 4900);
DISPLAY 1.021277 (450 4900);
PAINT PURPLE (450 4900);
FORCENOTE
(12 MM STACK)
(450 4825) 0;
DISPLAY LEFT (450 4825);
DISPLAY 1.021277 (450 4825);
PAINT PURPLE (450 4825);
FORCENOTE
FCI RECPT # ON CC
(-200 4900) 0;
DISPLAY LEFT (-200 4900);
DISPLAY 1.021277 (-200 4900);
PAINT PURPLE (-200 4900);
FORCENOTE
A28699-010
(-875 4725) 0;
DISPLAY LEFT (-875 4725);
DISPLAY 1.021277 (-875 4725);
PAINT PURPLE (-875 4725);
FORCENOTE
E67482-006
(-875 4625) 0;
DISPLAY LEFT (-875 4625);
DISPLAY 1.021277 (-875 4625);
PAINT PURPLE (-875 4625);
FORCENOTE
H87568-001
(-875 4525) 0;
DISPLAY LEFT (-875 4525);
DISPLAY 1.021277 (-875 4525);
PAINT PURPLE (-875 4525);
FORCENOTE
FCI RECPT # ON CC
(-1550 4900) 0;
DISPLAY LEFT (-1550 4900);
DISPLAY 1.021277 (-1550 4900);
PAINT PURPLE (-1550 4900);
FORCENOTE
CONN
(-3600 4900) 0;
DISPLAY LEFT (-3600 4900);
DISPLAY 1.021277 (-3600 4900);
PAINT PURPLE (-3600 4900);
FORCENOTE
ROOM = IO_MODULE
(-3600 400) 0;
DISPLAY LEFT (-3600 400);
DISPLAY 0.808511 (-3600 400);
PAINT PURPLE (-3600 400);
FORCENOTE
61083-121402LF
(-3275 4725) 0;
DISPLAY LEFT (-3275 4725);
DISPLAY 1.021277 (-3275 4725);
PAINT PURPLE (-3275 4725);
FORCENOTE
(5/8MM STACK)
(-1550 4825) 0;
DISPLAY LEFT (-1550 4825);
DISPLAY 1.021277 (-1550 4825);
PAINT PURPLE (-1550 4825);
FORCENOTE
61082-081402LF
(-1550 4625) 0;
DISPLAY LEFT (-1550 4625);
DISPLAY 1.021277 (-1550 4625);
PAINT PURPLE (-1550 4625);
FORCENOTE
TP FAB1 ADD CAPS 0322
(2050 3925) 0;
DISPLAY LEFT (2050 3925);
DISPLAY 1.021277 (2050 3925);
PAINT RED (2050 3925);
FORCENOTE
10135583-641402LF
(-1550 4525) 0;
DISPLAY LEFT (-1550 4525);
DISPLAY 1.021277 (-1550 4525);
PAINT PURPLE (-1550 4525);
FORCENOTE
61083-124402LF
(-2425 4725) 0;
DISPLAY LEFT (-2425 4725);
DISPLAY 1.021277 (-2425 4725);
PAINT PURPLE (-2425 4725);
FORCENOTE
(8/12 MM STACK)
(-2425 4825) 0;
DISPLAY LEFT (-2425 4825);
DISPLAY 1.021277 (-2425 4825);
PAINT PURPLE (-2425 4825);
FORCENOTE
FCI PLUG # ON OCP MEZZ
(-2425 4900) 0;
DISPLAY LEFT (-2425 4900);
DISPLAY 1.021277 (-2425 4900);
PAINT PURPLE (-2425 4900);
FORCENOTE
10135584-644402LF
(-2425 4525) 0;
DISPLAY LEFT (-2425 4525);
DISPLAY 1.021277 (-2425 4525);
PAINT PURPLE (-2425 4525);
FORCENOTE
TP FAB1 DELETE CONNECTION TO PCH 1230
(-2050 3550) 0;
DISPLAY LEFT (-2050 3550);
DISPLAY 0.510638 (-2050 3550);
PAINT RED (-2050 3550);
FORCENOTE
TP FAB1 DELETE TEST POINT 0121
(-2000 2575) 0;
DISPLAY LEFT (-2000 2575);
DISPLAY 0.638298 (-2000 2575);
PAINT RED (-2000 2575);
FORCENOTE
TP FAB3-DVT ADD 4.75KOHM RES R1W40, R1W41 20161205
(-3450 2450) 0;
DISPLAY LEFT (-3450 2450);
DISPLAY 0.638298 (-3450 2450);
PAINT RED (-3450 2450);
FORCENOTE
TP FAB1 DELETE TEST POINT 0121
(2350 3050) 0;
DISPLAY LEFT (2350 3050);
DISPLAY 1.021277 (2350 3050);
PAINT RED (2350 3050);
FORCENOTE
TP FAB1 PUT KR1 BACK 0322
(1800 3100) 0;
DISPLAY LEFT (1800 3100);
DISPLAY 0.808511 (1800 3100);
PAINT RED (1800 3100);
FORCENOTE
TP FAB1 DELETE CONNECTION TO PCH 1230
(1800 3150) 0;
DISPLAY LEFT (1800 3150);
DISPLAY 0.808511 (1800 3150);
PAINT RED (1800 3150);
FORCENOTE
TP FAB1 RENAME 1218
(750 2100) 0;
DISPLAY LEFT (750 2100);
DISPLAY 1.021277 (750 2100);
PAINT RED (750 2100);
FORCENOTE
TP FAB3-DVT ADD 4.75KOHM RES R1W42-45 20161206
(-3450 1800) 0;
DISPLAY LEFT (-3450 1800);
DISPLAY 0.638298 (-3450 1800);
PAINT RED (-3450 1800);
FORCENOTE
A28699-020
(450 4725) 0;
DISPLAY LEFT (450 4725);
DISPLAY 1.021277 (450 4725);
PAINT PURPLE (450 4725);
FORCENOTE
61083-084402LF
(-2425 4625) 0;
DISPLAY LEFT (-2425 4625);
DISPLAY 1.021277 (-2425 4625);
PAINT PURPLE (-2425 4625);
FORCENOTE
C (64P)
(-3600 4525) 0;
DISPLAY LEFT (-3600 4525);
DISPLAY 1.021277 (-3600 4525);
PAINT PURPLE (-3600 4525);
QUIT
